FILE_TYPE = MACRO_DRAWING;
SET COLOR_WIRE YELLOW;
SET COLOR_PROP MONO;
SET COLOR_DOT WHITE;
SET COLOR_ARC YELLOW;
SET COLOR_BODY GREEN;
SET COLOR_NOTE MONO;
SET PROP_DISPLAY VALUE;
SET PAGE_NUMBER P157;
FORCEADD OFFPAGE..2
(-5975 4225);
FORCEPROP 2 LAST $XR3 145 
J 0
(-5426 4225);
DISPLAY 0.638298 (-5426 4225);
PAINT MONO (-5426 4225);
FORCEPROP 2 LAST $XR2 119 
J 0
(-5546 4225);
DISPLAY 0.638298 (-5546 4225);
PAINT MONO (-5546 4225);
FORCEPROP 2 LAST $XR1 186 
J 0
(-5666 4225);
DISPLAY 0.638298 (-5666 4225);
PAINT MONO (-5666 4225);
FORCEPROP 2 LAST $XR0 185 
J 0
(-5786 4225);
DISPLAY 0.638298 (-5786 4225);
PAINT MONO (-5786 4225);
FORCEPROP 2 LAST PATH I293
J 0
(-5800 4300);
DISPLAY 1.021277 (-5800 4300);
PAINT ORANGE (-5800 4300);
DISPLAY INVISIBLE (-5800 4300);
FORCEPROP 1 LAST OFFPAGE TRUE
J 0
(-5650 4100);
DISPLAY 0.872340 (-5650 4100);
PAINT GREEN (-5650 4100);
DISPLAY INVISIBLE (-5650 4100);
FORCEPROP 1 LAST COMMENT_BODY TRUE
J 0
(-6020 4130);
DISPLAY 0.872340 (-6020 4130);
PAINT GREEN (-6020 4130);
DISPLAY INVISIBLE (-6020 4130);
FORCEPROP 2 LAST CDS_LIB mstr_standard
J 0
(-5975 4225);
PAINT ORANGE (-5975 4225);
DISPLAY INVISIBLE (-5975 4225);
FORCEADD RES..1
(-7200 4225);
FORCEPROP 1 LAST MATERIAL CHIP
J 0
(-6950 4150);
DISPLAY 0.617021 (-6950 4150);
PAINT SKYBLUE (-6950 4150);
FORCEPROP 1 LAST PACK_TYPE 0402
J 0
(-7025 4175);
DISPLAY 0.617021 (-7025 4175);
PAINT SKYBLUE (-7025 4175);
FORCEPROP 1 LAST TOLERANCE 1%
J 0
(-7150 4175);
DISPLAY 0.617021 (-7150 4175);
PAINT SKYBLUE (-7150 4175);
FORCEPROP 1 LAST VALUE 2.21K
J 2
(-7225 4175);
DISPLAY 0.617021 (-7225 4175);
PAINT SKYBLUE (-7225 4175);
FORCEPROP 1 LAST PART_NUMBER G21796-112
J 0
(-7425 4125);
DISPLAY 0.617021 (-7425 4125);
PAINT BLUE (-7425 4125);
FORCEPROP 1 LASTPIN (-7100 4225) $PN 2
J 0
(-7138 4237);
DISPLAY 0.617021 (-7138 4237);
PAINT ORANGE (-7138 4237);
FORCEPROP 1 LAST WATTAGE 1/16W
J 2
(-6750 4175);
DISPLAY 0.617021 (-6750 4175);
PAINT SKYBLUE (-6750 4175);
FORCEPROP 1 LAST LOCATION R8F23
J 0
(-7250 4275);
DISPLAY 0.617021 (-7250 4275);
PAINT AQUA (-7250 4275);
FORCEPROP 1 LASTPIN (-7300 4225) $PN 1
J 0
(-7288 4237);
DISPLAY 0.617021 (-7288 4237);
PAINT ORANGE (-7288 4237);
FORCEPROP 2 LAST BOM_COST SM_CONTROLLER
J 0
(-7250 4375);
DISPLAY 1.021277 (-7250 4375);
PAINT ORANGE (-7250 4375);
DISPLAY INVISIBLE (-7250 4375);
FORCEPROP 2 LAST SEC_TYPE 0402
J 0
(-7250 4425);
DISPLAY 1.021277 (-7250 4425);
PAINT ORANGE (-7250 4425);
DISPLAY INVISIBLE (-7250 4425);
FORCEPROP 1 LAST PATH I296
J 0
(-7250 4375);
DISPLAY 0.978723 (-7250 4375);
PAINT WHITE (-7250 4375);
DISPLAY INVISIBLE (-7250 4375);
FORCEPROP 0 LAST SEC 1
J 0
(-7250 4325);
DISPLAY 0.680851 (-7250 4325);
PAINT MONO (-7250 4325);
DISPLAY INVISIBLE (-7250 4325);
FORCEPROP 2 LAST ROOM BMC_MISC
J 0
(-7250 4325);
DISPLAY 1.021277 (-7250 4325);
PAINT ORANGE (-7250 4325);
DISPLAY INVISIBLE (-7250 4325);
FORCEPROP 2 LAST CDS_LOCATION R8F23
J 0
(-7250 4275);
DISPLAY 0.617021 (-7250 4275);
PAINT AQUA (-7250 4275);
DISPLAY INVISIBLE (-7250 4275);
FORCEPROP 2 LAST CDS_LIB mstr_discrete
J 0
(-7200 4225);
PAINT ORANGE (-7200 4225);
DISPLAY INVISIBLE (-7200 4225);
FORCEADD P3V3_STBY..1
(-7525 4650);
FORCEPROP 3 LASTPIN (-7525 4600) SIG_NAME P3V3_STBY\g
J 0
(-7515 4610);
DISPLAY 0.659574 (-7515 4610);
PAINT MONO (-7515 4610);
DISPLAY INVISIBLE (-7515 4610);
FORCEPROP 2 LAST CDS_LIB mstr_symbols
J 0
(-7525 4650);
PAINT ORANGE (-7525 4650);
DISPLAY INVISIBLE (-7525 4650);
FORCEPROP 1 LAST SIZE 1B
J 0
(-7480 4672);
DISPLAY 0.340426 (-7480 4672);
PAINT GREEN (-7480 4672);
DISPLAY INVISIBLE (-7480 4672);
FORCEPROP 1 LAST PATH I297
J 0
(-7480 4652);
DISPLAY 0.340426 (-7480 4652);
PAINT GREEN (-7480 4652);
DISPLAY INVISIBLE (-7480 4652);
FORCEPROP 1 LAST VOLTAGE 3.3V
J 0
(-7570 4607);
DISPLAY 0.340426 (-7570 4607);
PAINT SKYBLUE (-7570 4607);
DISPLAY INVISIBLE (-7570 4607);
FORCEPROP 1 LAST BODY_TYPE PLUMBING
J 0
(-7570 4607);
DISPLAY 0.340426 (-7570 4607);
PAINT GREEN (-7570 4607);
DISPLAY INVISIBLE (-7570 4607);
FORCEPROP 1 LAST HDL_POWER P3V3_STBY
J 0
(-7825 4525);
DISPLAY 0.872340 (-7825 4525);
PAINT ORANGE (-7825 4525);
DISPLAY INVISIBLE (-7825 4525);
FORCEADD RES..1
(-7175 3975);
FORCEPROP 1 LAST PART_NUMBER G21796-112
J 0
(-7400 3875);
DISPLAY 0.617021 (-7400 3875);
PAINT BLUE (-7400 3875);
FORCEPROP 1 LAST MATERIAL CHIP
J 0
(-6925 3900);
DISPLAY 0.617021 (-6925 3900);
PAINT SKYBLUE (-6925 3900);
FORCEPROP 1 LAST WATTAGE 1/16W
J 2
(-6725 3925);
DISPLAY 0.617021 (-6725 3925);
PAINT SKYBLUE (-6725 3925);
FORCEPROP 1 LAST PACK_TYPE 0402
J 0
(-7000 3925);
DISPLAY 0.617021 (-7000 3925);
PAINT SKYBLUE (-7000 3925);
FORCEPROP 1 LAST TOLERANCE 1%
J 0
(-7125 3925);
DISPLAY 0.617021 (-7125 3925);
PAINT SKYBLUE (-7125 3925);
FORCEPROP 1 LAST VALUE 2.21K
J 2
(-7200 3925);
DISPLAY 0.617021 (-7200 3925);
PAINT SKYBLUE (-7200 3925);
FORCEPROP 1 LASTPIN (-7275 3975) $PN 1
J 0
(-7263 3987);
DISPLAY 0.617021 (-7263 3987);
PAINT ORANGE (-7263 3987);
FORCEPROP 1 LAST LOCATION R2T29
J 0
(-7225 4025);
DISPLAY 0.617021 (-7225 4025);
PAINT AQUA (-7225 4025);
FORCEPROP 1 LASTPIN (-7075 3975) $PN 2
J 0
(-7113 3987);
DISPLAY 0.617021 (-7113 3987);
PAINT ORANGE (-7113 3987);
FORCEPROP 2 LAST BOM_COST SM_CONTROLLER
J 0
(-7225 4125);
DISPLAY 1.021277 (-7225 4125);
PAINT ORANGE (-7225 4125);
DISPLAY INVISIBLE (-7225 4125);
FORCEPROP 1 LAST PATH I298
J 0
(-7225 4125);
DISPLAY 0.978723 (-7225 4125);
PAINT WHITE (-7225 4125);
DISPLAY INVISIBLE (-7225 4125);
FORCEPROP 2 LAST SEC_TYPE 0402
J 0
(-7225 4175);
DISPLAY 1.021277 (-7225 4175);
PAINT ORANGE (-7225 4175);
DISPLAY INVISIBLE (-7225 4175);
FORCEPROP 0 LAST SEC 1
J 0
(-7225 4075);
DISPLAY 0.680851 (-7225 4075);
PAINT MONO (-7225 4075);
DISPLAY INVISIBLE (-7225 4075);
FORCEPROP 2 LAST ROOM BMC_MISC
J 0
(-7225 4075);
DISPLAY 1.021277 (-7225 4075);
PAINT ORANGE (-7225 4075);
DISPLAY INVISIBLE (-7225 4075);
FORCEPROP 2 LAST CDS_LIB mstr_discrete
J 0
(-7175 3975);
PAINT ORANGE (-7175 3975);
DISPLAY INVISIBLE (-7175 3975);
FORCEPROP 2 LAST CDS_LOCATION R2T29
J 0
(-7225 4025);
DISPLAY 0.617021 (-7225 4025);
PAINT AQUA (-7225 4025);
DISPLAY INVISIBLE (-7225 4025);
FORCEADD OFFPAGE..2
(-5950 3975);
FORCEPROP 2 LAST $XR2 145 
J 0
(-5521 3975);
DISPLAY 0.638298 (-5521 3975);
PAINT MONO (-5521 3975);
FORCEPROP 2 LAST $XR1 119 
J 0
(-5641 3975);
DISPLAY 0.638298 (-5641 3975);
PAINT MONO (-5641 3975);
FORCEPROP 2 LAST $XR0 108 
J 0
(-5761 3975);
DISPLAY 0.638298 (-5761 3975);
PAINT MONO (-5761 3975);
FORCEPROP 1 LAST OFFPAGE TRUE
J 0
(-5625 3850);
DISPLAY 0.872340 (-5625 3850);
PAINT GREEN (-5625 3850);
DISPLAY INVISIBLE (-5625 3850);
FORCEPROP 2 LAST PATH I299
J 0
(-5775 4050);
DISPLAY 1.021277 (-5775 4050);
PAINT ORANGE (-5775 4050);
DISPLAY INVISIBLE (-5775 4050);
FORCEPROP 1 LAST COMMENT_BODY TRUE
J 0
(-5995 3880);
DISPLAY 0.872340 (-5995 3880);
PAINT GREEN (-5995 3880);
DISPLAY INVISIBLE (-5995 3880);
FORCEPROP 2 LAST CDS_LIB mstr_standard
J 0
(-5950 3975);
PAINT ORANGE (-5950 3975);
DISPLAY INVISIBLE (-5950 3975);
FORCEADD OFFPAGE..2
(-1250 3825);
FORCEPROP 2 LAST $XR1 146 
J 0
(-941 3825);
DISPLAY 0.638298 (-941 3825);
PAINT MONO (-941 3825);
FORCEPROP 2 LAST $XR0 120 
J 0
(-1061 3825);
DISPLAY 0.638298 (-1061 3825);
PAINT MONO (-1061 3825);
FORCEPROP 1 LAST OFFPAGE TRUE
J 0
(-925 3700);
DISPLAY 0.872340 (-925 3700);
PAINT GREEN (-925 3700);
DISPLAY INVISIBLE (-925 3700);
FORCEPROP 2 LAST PATH I300
J 0
(-1200 3900);
DISPLAY 1.021277 (-1200 3900);
PAINT ORANGE (-1200 3900);
DISPLAY INVISIBLE (-1200 3900);
FORCEPROP 2 LAST CDS_LIB mstr_standard
J 0
(-1250 3825);
PAINT ORANGE (-1250 3825);
DISPLAY INVISIBLE (-1250 3825);
FORCEPROP 1 LAST COMMENT_BODY TRUE
J 0
(-1295 3730);
DISPLAY 0.872340 (-1295 3730);
PAINT GREEN (-1295 3730);
DISPLAY INVISIBLE (-1295 3730);
FORCEADD OFFPAGE..1
(-2900 3825);
FORCEPROP 2 LAST $XR0 120 
J 0
(-3152 3825);
DISPLAY 0.638298 (-3152 3825);
PAINT MONO (-3152 3825);
FORCEPROP 1 LAST COMMENT_BODY TRUE
J 0
(-2775 3725);
DISPLAY 0.872340 (-2775 3725);
PAINT GREEN (-2775 3725);
DISPLAY INVISIBLE (-2775 3725);
FORCEPROP 1 LAST OFFPAGE TRUE
J 0
(-2575 3700);
DISPLAY 0.872340 (-2575 3700);
PAINT GREEN (-2575 3700);
DISPLAY INVISIBLE (-2575 3700);
FORCEPROP 2 LAST PATH I301
J 0
(-2850 3900);
DISPLAY 1.021277 (-2850 3900);
PAINT ORANGE (-2850 3900);
DISPLAY INVISIBLE (-2850 3900);
FORCEPROP 2 LAST CDS_LIB mstr_standard
J 0
(-2900 3825);
PAINT ORANGE (-2900 3825);
DISPLAY INVISIBLE (-2900 3825);
FORCEADD RES..1
(-2050 3825);
FORCEPROP 1 LAST MATERIAL CHIP
J 0
(-1975 3725);
DISPLAY 0.617021 (-1975 3725);
PAINT SKYBLUE (-1975 3725);
FORCEPROP 1 LAST WATTAGE 1/16W
J 2
(-1775 3775);
DISPLAY 0.617021 (-1775 3775);
PAINT SKYBLUE (-1775 3775);
FORCEPROP 1 LAST PART_NUMBER G21796-208
J 0
(-2275 3725);
DISPLAY 0.617021 (-2275 3725);
PAINT BLUE (-2275 3725);
FORCEPROP 1 LAST VALUE 51.1
J 2
(-2075 3775);
DISPLAY 0.617021 (-2075 3775);
PAINT SKYBLUE (-2075 3775);
FORCEPROP 1 LAST LOCATION R2N25
J 0
(-2100 3875);
DISPLAY 0.617021 (-2100 3875);
PAINT AQUA (-2100 3875);
FORCEPROP 1 LAST TOLERANCE 1.0%
J 0
(-2000 3775);
DISPLAY 0.617021 (-2000 3775);
PAINT SKYBLUE (-2000 3775);
FORCEPROP 1 LAST PACK_TYPE 0402
J 0
(-1750 3775);
DISPLAY 0.617021 (-1750 3775);
PAINT SKYBLUE (-1750 3775);
FORCEPROP 1 LASTPIN (-1950 3825) $PN 2
J 0
(-1988 3837);
DISPLAY 0.617021 (-1988 3837);
PAINT ORANGE (-1988 3837);
FORCEPROP 1 LASTPIN (-2150 3825) $PN 1
J 0
(-2138 3837);
DISPLAY 0.617021 (-2138 3837);
PAINT ORANGE (-2138 3837);
FORCEPROP 0 LAST BOM_COST SM_CONTROLLER
J 0
(-2100 4125);
DISPLAY 1.021277 (-2100 4125);
PAINT ORANGE (-2100 4125);
DISPLAY INVISIBLE (-2100 4125);
FORCEPROP 0 LAST ROOM BMC_MISC
J 0
(-2100 4025);
DISPLAY 1.021277 (-2100 4025);
PAINT ORANGE (-2100 4025);
DISPLAY INVISIBLE (-2100 4025);
FORCEPROP 1 LAST PATH I302
J 0
(-2100 3975);
DISPLAY 0.978723 (-2100 3975);
PAINT WHITE (-2100 3975);
DISPLAY INVISIBLE (-2100 3975);
FORCEPROP 2 LAST CDS_LOCATION R2N25
J 0
(-2100 3875);
DISPLAY 0.617021 (-2100 3875);
PAINT AQUA (-2100 3875);
DISPLAY INVISIBLE (-2100 3875);
FORCEPROP 2 LAST SEC 1
J 0
(-2100 4025);
DISPLAY 0.680851 (-2100 4025);
PAINT MONO (-2100 4025);
DISPLAY INVISIBLE (-2100 4025);
FORCEPROP 2 LAST SEC_TYPE 0402
J 0
(-2100 4025);
DISPLAY 1.021277 (-2100 4025);
PAINT ORANGE (-2100 4025);
DISPLAY INVISIBLE (-2100 4025);
FORCEPROP 2 LAST CDS_LIB mstr_discrete
J 0
(-2050 3825);
PAINT ORANGE (-2050 3825);
DISPLAY INVISIBLE (-2050 3825);
FORCEADD P3V3..1
(-1850 4275);
FORCEPROP 3 LASTPIN (-1850 4225) SIG_NAME P3V3\g
J 0
(-1840 4235);
DISPLAY 0.659574 (-1840 4235);
PAINT MONO (-1840 4235);
DISPLAY INVISIBLE (-1840 4235);
FORCEPROP 1 LAST BODY_TYPE PLUMBING
J 0
(-1895 4232);
DISPLAY 0.340426 (-1895 4232);
PAINT GREEN (-1895 4232);
DISPLAY INVISIBLE (-1895 4232);
FORCEPROP 2 LAST CDS_LIB mstr_symbols
J 0
(-1850 4275);
PAINT ORANGE (-1850 4275);
DISPLAY INVISIBLE (-1850 4275);
FORCEPROP 1 LAST SIZE 1B
J 0
(-1805 4297);
DISPLAY 0.340426 (-1805 4297);
PAINT GREEN (-1805 4297);
DISPLAY INVISIBLE (-1805 4297);
FORCEPROP 1 LAST VOLTAGE 3.3V
J 0
(-1895 4232);
DISPLAY 0.340426 (-1895 4232);
PAINT SKYBLUE (-1895 4232);
DISPLAY INVISIBLE (-1895 4232);
FORCEPROP 1 LAST PATH I303
J 0
(-1805 4277);
DISPLAY 0.340426 (-1805 4277);
PAINT GREEN (-1805 4277);
DISPLAY INVISIBLE (-1805 4277);
FORCEPROP 1 LAST HDL_POWER P3V3
J 0
(-2175 4150);
DISPLAY 0.872340 (-2175 4150);
PAINT ORANGE (-2175 4150);
DISPLAY INVISIBLE (-2175 4150);
FORCEADD RES..1
(-7175 3725);
FORCEPROP 1 LAST MATERIAL CHIP
J 0
(-6925 3625);
DISPLAY 0.617021 (-6925 3625);
PAINT SKYBLUE (-6925 3625);
FORCEPROP 1 LAST PACK_TYPE 0402
J 0
(-7000 3675);
DISPLAY 0.617021 (-7000 3675);
PAINT SKYBLUE (-7000 3675);
FORCEPROP 1 LAST TOLERANCE 1%
J 0
(-7125 3675);
DISPLAY 0.617021 (-7125 3675);
PAINT SKYBLUE (-7125 3675);
FORCEPROP 1 LAST PART_NUMBER G21796-072
J 0
(-7400 3625);
DISPLAY 0.617021 (-7400 3625);
PAINT BLUE (-7400 3625);
FORCEPROP 1 LAST VALUE 4.75K
J 2
(-7200 3675);
DISPLAY 0.617021 (-7200 3675);
PAINT SKYBLUE (-7200 3675);
FORCEPROP 1 LASTPIN (-7275 3725) $PN 1
J 0
(-7263 3737);
DISPLAY 0.617021 (-7263 3737);
PAINT ORANGE (-7263 3737);
FORCEPROP 1 LAST WATTAGE 1/16W
J 2
(-6750 3675);
DISPLAY 0.617021 (-6750 3675);
PAINT SKYBLUE (-6750 3675);
FORCEPROP 1 LASTPIN (-7075 3725) $PN 2
J 0
(-7113 3737);
DISPLAY 0.617021 (-7113 3737);
PAINT ORANGE (-7113 3737);
FORCEPROP 1 LAST LOCATION R8F24
J 0
(-7225 3775);
DISPLAY 0.617021 (-7225 3775);
PAINT AQUA (-7225 3775);
FORCEPROP 2 LAST BOM_COST SM_CONTROLLER
J 0
(-7225 3875);
DISPLAY 1.021277 (-7225 3875);
PAINT ORANGE (-7225 3875);
DISPLAY INVISIBLE (-7225 3875);
FORCEPROP 1 LAST PATH I316
J 0
(-7225 3875);
DISPLAY 0.978723 (-7225 3875);
PAINT WHITE (-7225 3875);
DISPLAY INVISIBLE (-7225 3875);
FORCEPROP 2 LAST SEC 1
J 0
(-7225 3925);
PAINT MONO (-7225 3925);
DISPLAY INVISIBLE (-7225 3925);
FORCEPROP 2 LAST SEC_TYPE 0402
J 0
(-7225 3925);
DISPLAY 1.021277 (-7225 3925);
PAINT ORANGE (-7225 3925);
DISPLAY INVISIBLE (-7225 3925);
FORCEPROP 2 LAST ROOM BMC_MISC
J 0
(-7225 3825);
DISPLAY 1.021277 (-7225 3825);
PAINT ORANGE (-7225 3825);
DISPLAY INVISIBLE (-7225 3825);
FORCEPROP 2 LAST CDS_LIB mstr_discrete
J 0
(-7175 3725);
PAINT ORANGE (-7175 3725);
DISPLAY INVISIBLE (-7175 3725);
FORCEPROP 2 LAST CDS_LOCATION R8F24
J 0
(-7225 3775);
DISPLAY 0.617021 (-7225 3775);
PAINT AQUA (-7225 3775);
DISPLAY INVISIBLE (-7225 3775);
FORCEADD OFFPAGE..2
(-5950 3725);
FORCEPROP 2 LAST $XR2 145 
J 0
(-5521 3725);
DISPLAY 0.638298 (-5521 3725);
PAINT MONO (-5521 3725);
FORCEPROP 2 LAST $XR1 119 
J 0
(-5641 3725);
DISPLAY 0.638298 (-5641 3725);
PAINT MONO (-5641 3725);
FORCEPROP 2 LAST $XR0 157 
J 0
(-5761 3725);
DISPLAY 0.638298 (-5761 3725);
PAINT MONO (-5761 3725);
FORCEPROP 1 LAST OFFPAGE TRUE
J 0
(-5625 3600);
DISPLAY 0.872340 (-5625 3600);
PAINT GREEN (-5625 3600);
DISPLAY INVISIBLE (-5625 3600);
FORCEPROP 2 LAST PATH I317
J 0
(-5900 3800);
DISPLAY 1.021277 (-5900 3800);
PAINT ORANGE (-5900 3800);
DISPLAY INVISIBLE (-5900 3800);
FORCEPROP 2 LAST CDS_LIB mstr_standard
J 0
(-5950 3725);
PAINT ORANGE (-5950 3725);
DISPLAY INVISIBLE (-5950 3725);
FORCEPROP 1 LAST COMMENT_BODY TRUE
J 0
(-5995 3630);
DISPLAY 0.872340 (-5995 3630);
PAINT GREEN (-5995 3630);
DISPLAY INVISIBLE (-5995 3630);
FORCEADD GND..1
(-6150 525);
FORCEPROP 3 LASTPIN (-6150 575) SIG_NAME GND\g
J 0
(-6140 585);
DISPLAY 0.659574 (-6140 585);
PAINT MONO (-6140 585);
DISPLAY INVISIBLE (-6140 585);
FORCEPROP 1 LAST BODY_TYPE PLUMBING
J 0
(-6195 482);
DISPLAY 0.340426 (-6195 482);
PAINT GREEN (-6195 482);
DISPLAY INVISIBLE (-6195 482);
FORCEPROP 1 LAST SIZE 1B
J 0
(-6075 475);
DISPLAY 0.872340 (-6075 475);
PAINT AQUA (-6075 475);
DISPLAY INVISIBLE (-6075 475);
FORCEPROP 1 LAST VOLTAGE 0.0V
J 0
(-6195 482);
DISPLAY 0.340426 (-6195 482);
PAINT SKYBLUE (-6195 482);
DISPLAY INVISIBLE (-6195 482);
FORCEPROP 1 LAST PATH I322
J 0
(-6075 525);
DISPLAY 0.872340 (-6075 525);
PAINT AQUA (-6075 525);
DISPLAY INVISIBLE (-6075 525);
FORCEPROP 2 LAST CDS_LIB mstr_symbols
J 0
(-6150 525);
PAINT MONO (-6150 525);
DISPLAY INVISIBLE (-6150 525);
FORCEPROP 1 LAST HDL_POWER GND
J 0
(-6150 675);
DISPLAY 0.872340 (-6150 675);
PAINT GREEN (-6150 675);
DISPLAY INVISIBLE (-6150 675);
FORCEADD OFFPAGE..1
(-7575 775);
FORCEPROP 2 LAST $XR1 97 
J 0
(-7886 775);
DISPLAY 0.638298 (-7886 775);
PAINT MONO (-7886 775);
FORCEPROP 2 LAST $XR0 21 
J 0
(-7796 775);
DISPLAY 0.638298 (-7796 775);
PAINT MONO (-7796 775);
FORCEPROP 2 LAST PATH I324
J 0
(-7525 850);
DISPLAY 1.021277 (-7525 850);
PAINT ORANGE (-7525 850);
DISPLAY INVISIBLE (-7525 850);
FORCEPROP 1 LAST COMMENT_BODY TRUE
J 0
(-7450 675);
DISPLAY 0.872340 (-7450 675);
PAINT GREEN (-7450 675);
DISPLAY INVISIBLE (-7450 675);
FORCEPROP 1 LAST OFFPAGE TRUE
J 0
(-7250 650);
DISPLAY 0.872340 (-7250 650);
PAINT GREEN (-7250 650);
DISPLAY INVISIBLE (-7250 650);
FORCEPROP 2 LAST CDS_LIB mstr_standard
J 0
(-7575 775);
PAINT MONO (-7575 775);
DISPLAY INVISIBLE (-7575 775);
FORCEADD OFFPAGE..2
(-4775 1425);
FORCEPROP 2 LAST $XR1 144 
J 0
(-4586 1389);
DISPLAY 0.638298 (-4586 1389);
PAINT MONO (-4586 1389);
FORCEPROP 2 LAST $XR0 119 
J 0
(-4586 1425);
DISPLAY 0.638298 (-4586 1425);
PAINT MONO (-4586 1425);
FORCEPROP 1 LAST COMMENT_BODY TRUE
J 0
(-4820 1330);
DISPLAY 0.872340 (-4820 1330);
PAINT GREEN (-4820 1330);
DISPLAY INVISIBLE (-4820 1330);
FORCEPROP 2 LAST CDS_LIB mstr_standard
J 0
(-4775 1425);
PAINT MONO (-4775 1425);
DISPLAY INVISIBLE (-4775 1425);
FORCEPROP 2 LAST PATH I325
J 0
(-4725 1500);
DISPLAY 1.021277 (-4725 1500);
PAINT ORANGE (-4725 1500);
DISPLAY INVISIBLE (-4725 1500);
FORCEPROP 1 LAST OFFPAGE TRUE
J 0
(-4450 1300);
DISPLAY 0.872340 (-4450 1300);
PAINT GREEN (-4450 1300);
DISPLAY INVISIBLE (-4450 1300);
FORCEADD RES..2
(-6150 1250);
FORCEPROP 1 LAST PACK_TYPE 0402
J 0
(-6110 1075);
DISPLAY 0.617021 (-6110 1075);
PAINT SKYBLUE (-6110 1075);
FORCEPROP 1 LAST PART_NUMBER G21796-026
J 0
(-6110 1125);
DISPLAY 0.617021 (-6110 1125);
PAINT BLUE (-6110 1125);
FORCEPROP 1 LAST MATERIAL CHIP
J 0
(-6110 1175);
DISPLAY 0.617021 (-6110 1175);
PAINT SKYBLUE (-6110 1175);
FORCEPROP 1 LAST WATTAGE 1/16W
J 0
(-6110 1225);
DISPLAY 0.617021 (-6110 1225);
PAINT SKYBLUE (-6110 1225);
FORCEPROP 1 LAST TOLERANCE 1%
J 0
(-6105 1275);
DISPLAY 0.617021 (-6105 1275);
PAINT SKYBLUE (-6105 1275);
FORCEPROP 1 LAST VALUE 1.00K
J 0
(-6105 1325);
DISPLAY 0.617021 (-6105 1325);
PAINT SKYBLUE (-6105 1325);
FORCEPROP 1 LAST LOCATION R2T5
J 0
(-6105 1375);
DISPLAY 0.617021 (-6105 1375);
PAINT AQUA (-6105 1375);
FORCEPROP 1 LASTPIN (-6150 1150) $PN 2
J 0
(-6145 1160);
DISPLAY 0.617021 (-6145 1160);
PAINT ORANGE (-6145 1160);
FORCEPROP 1 LASTPIN (-6150 1350) $PN 1
J 0
(-6145 1312);
DISPLAY 0.617021 (-6145 1312);
PAINT ORANGE (-6145 1312);
FORCEPROP 2 LAST CDS_LIB mstr_discrete
J 0
(-6150 1250);
PAINT MONO (-6150 1250);
DISPLAY INVISIBLE (-6150 1250);
FORCEPROP 2 LAST CDS_LOCATION R2T5
J 0
(-6105 1375);
DISPLAY 0.617021 (-6105 1375);
PAINT AQUA (-6105 1375);
DISPLAY INVISIBLE (-6105 1375);
FORCEPROP 0 LAST ROOM PROC_SIDEBAND
J 0
(-6100 1475);
DISPLAY 1.021277 (-6100 1475);
PAINT ORANGE (-6100 1475);
DISPLAY INVISIBLE (-6100 1475);
FORCEPROP 1 LAST PATH I326
J 0
(-6100 1425);
DISPLAY 0.978723 (-6100 1425);
PAINT WHITE (-6100 1425);
DISPLAY INVISIBLE (-6100 1425);
FORCEPROP 2 LAST SEC 1
J 0
(-6100 1475);
DISPLAY 0.680851 (-6100 1475);
PAINT MONO (-6100 1475);
DISPLAY INVISIBLE (-6100 1475);
FORCEPROP 2 LAST SEC_TYPE 0402
J 0
(-6100 1475);
DISPLAY 1.021277 (-6100 1475);
PAINT ORANGE (-6100 1475);
DISPLAY INVISIBLE (-6100 1475);
FORCEPROP 0 LAST BOM_COST PROC_SIDEBAND
J 0
(-6100 1575);
DISPLAY 1.021277 (-6100 1575);
PAINT ORANGE (-6100 1575);
DISPLAY INVISIBLE (-6100 1575);
FORCEADD RES..2
(-5500 1650);
FORCEPROP 1 LAST PACK_TYPE 0402
J 0
(-5460 1475);
DISPLAY 0.617021 (-5460 1475);
PAINT SKYBLUE (-5460 1475);
FORCEPROP 1 LAST PART_NUMBER G21796-026
J 0
(-5460 1525);
DISPLAY 0.617021 (-5460 1525);
PAINT BLUE (-5460 1525);
FORCEPROP 1 LAST MATERIAL CHIP
J 0
(-5460 1575);
DISPLAY 0.617021 (-5460 1575);
PAINT SKYBLUE (-5460 1575);
FORCEPROP 1 LAST WATTAGE 1/16W
J 0
(-5460 1625);
DISPLAY 0.617021 (-5460 1625);
PAINT SKYBLUE (-5460 1625);
FORCEPROP 1 LAST TOLERANCE 1%
J 0
(-5455 1675);
DISPLAY 0.617021 (-5455 1675);
PAINT SKYBLUE (-5455 1675);
FORCEPROP 1 LAST VALUE 1.00K
J 0
(-5455 1725);
DISPLAY 0.617021 (-5455 1725);
PAINT SKYBLUE (-5455 1725);
FORCEPROP 1 LAST LOCATION R2T7
J 0
(-5455 1775);
DISPLAY 0.617021 (-5455 1775);
PAINT AQUA (-5455 1775);
FORCEPROP 1 LASTPIN (-5500 1550) $PN 2
J 0
(-5495 1560);
DISPLAY 0.617021 (-5495 1560);
PAINT ORANGE (-5495 1560);
FORCEPROP 1 LASTPIN (-5500 1750) $PN 1
J 0
(-5495 1712);
DISPLAY 0.617021 (-5495 1712);
PAINT ORANGE (-5495 1712);
FORCEPROP 2 LAST CDS_LIB mstr_discrete
J 0
(-5500 1650);
PAINT MONO (-5500 1650);
DISPLAY INVISIBLE (-5500 1650);
FORCEPROP 2 LAST CDS_LOCATION R2T7
J 0
(-5455 1775);
DISPLAY 0.617021 (-5455 1775);
PAINT AQUA (-5455 1775);
DISPLAY INVISIBLE (-5455 1775);
FORCEPROP 0 LAST ROOM PROC_SIDEBAND
J 0
(-5450 1875);
DISPLAY 1.021277 (-5450 1875);
PAINT ORANGE (-5450 1875);
DISPLAY INVISIBLE (-5450 1875);
FORCEPROP 1 LAST PATH I327
J 0
(-5450 1825);
DISPLAY 0.978723 (-5450 1825);
PAINT WHITE (-5450 1825);
DISPLAY INVISIBLE (-5450 1825);
FORCEPROP 2 LAST SEC 1
J 0
(-5450 1875);
DISPLAY 0.680851 (-5450 1875);
PAINT MONO (-5450 1875);
DISPLAY INVISIBLE (-5450 1875);
FORCEPROP 2 LAST SEC_TYPE 0402
J 0
(-5450 1875);
DISPLAY 1.021277 (-5450 1875);
PAINT ORANGE (-5450 1875);
DISPLAY INVISIBLE (-5450 1875);
FORCEPROP 0 LAST BOM_COST PROC_SIDEBAND
J 0
(-5450 1975);
DISPLAY 1.021277 (-5450 1975);
PAINT ORANGE (-5450 1975);
DISPLAY INVISIBLE (-5450 1975);
FORCEADD P3V3_STBY..1
(-6150 1450);
FORCEPROP 3 LASTPIN (-6150 1400) SIG_NAME P3V3_STBY\g
J 0
(-6140 1410);
DISPLAY 0.659574 (-6140 1410);
PAINT MONO (-6140 1410);
DISPLAY INVISIBLE (-6140 1410);
FORCEPROP 1 LAST HDL_POWER P3V3_STBY
J 0
(-6450 1325);
DISPLAY 0.872340 (-6450 1325);
PAINT ORANGE (-6450 1325);
DISPLAY INVISIBLE (-6450 1325);
FORCEPROP 1 LAST BODY_TYPE PLUMBING
J 0
(-6195 1407);
DISPLAY 0.340426 (-6195 1407);
PAINT GREEN (-6195 1407);
DISPLAY INVISIBLE (-6195 1407);
FORCEPROP 1 LAST VOLTAGE 3.3V
J 0
(-6195 1407);
DISPLAY 0.340426 (-6195 1407);
PAINT SKYBLUE (-6195 1407);
DISPLAY INVISIBLE (-6195 1407);
FORCEPROP 1 LAST PATH I328
J 0
(-6105 1452);
DISPLAY 0.340426 (-6105 1452);
PAINT GREEN (-6105 1452);
DISPLAY INVISIBLE (-6105 1452);
FORCEPROP 1 LAST SIZE 1B
J 0
(-6105 1472);
DISPLAY 0.340426 (-6105 1472);
PAINT GREEN (-6105 1472);
DISPLAY INVISIBLE (-6105 1472);
FORCEPROP 2 LAST CDS_LIB mstr_symbols
J 0
(-6150 1450);
PAINT MONO (-6150 1450);
DISPLAY INVISIBLE (-6150 1450);
FORCEADD P3V3_STBY..1
(-5500 1875);
FORCEPROP 3 LASTPIN (-5500 1825) SIG_NAME P3V3_STBY\g
J 0
(-5490 1835);
DISPLAY 0.659574 (-5490 1835);
PAINT MONO (-5490 1835);
DISPLAY INVISIBLE (-5490 1835);
FORCEPROP 1 LAST HDL_POWER P3V3_STBY
J 0
(-5800 1750);
DISPLAY 0.872340 (-5800 1750);
PAINT ORANGE (-5800 1750);
DISPLAY INVISIBLE (-5800 1750);
FORCEPROP 1 LAST PATH I329
J 0
(-5455 1877);
DISPLAY 0.340426 (-5455 1877);
PAINT GREEN (-5455 1877);
DISPLAY INVISIBLE (-5455 1877);
FORCEPROP 1 LAST BODY_TYPE PLUMBING
J 0
(-5545 1832);
DISPLAY 0.340426 (-5545 1832);
PAINT GREEN (-5545 1832);
DISPLAY INVISIBLE (-5545 1832);
FORCEPROP 1 LAST SIZE 1B
J 0
(-5455 1897);
DISPLAY 0.340426 (-5455 1897);
PAINT GREEN (-5455 1897);
DISPLAY INVISIBLE (-5455 1897);
FORCEPROP 2 LAST CDS_LIB mstr_symbols
J 0
(-5500 1875);
PAINT MONO (-5500 1875);
DISPLAY INVISIBLE (-5500 1875);
FORCEPROP 1 LAST VOLTAGE 3.3V
J 0
(-5545 1832);
DISPLAY 0.340426 (-5545 1832);
PAINT SKYBLUE (-5545 1832);
DISPLAY INVISIBLE (-5545 1832);
FORCEADD NPN..1
(-6200 775);
FORCEPROP 1 LAST VALUE MMBT3904
J 0
(-6050 775);
DISPLAY 0.617021 (-6050 775);
PAINT SKYBLUE (-6050 775);
FORCEPROP 1 LAST LOCATION Q2T1
J 0
(-6050 825);
DISPLAY 0.617021 (-6050 825);
PAINT AQUA (-6050 825);
FORCEPROP 1 LASTPIN (-6300 775) $PN 1
J 0
(-6330 850);
DISPLAY 0.617021 (-6330 850);
PAINT GREEN (-6330 850);
FORCEPROP 1 LASTPIN (-6150 675) $PN 2
J 0
(-6125 625);
DISPLAY 0.617021 (-6125 625);
PAINT GREEN (-6125 625);
FORCEPROP 1 LASTPIN (-6150 875) $PN 3
J 0
(-6131 885);
DISPLAY 0.617021 (-6131 885);
PAINT GREEN (-6131 885);
FORCEPROP 1 LAST MATERIAL IC
J 0
(-6050 725);
DISPLAY 0.617021 (-6050 725);
PAINT SKYBLUE (-6050 725);
FORCEPROP 1 LAST PACK_TYPE SM
J 0
(-6050 675);
DISPLAY 0.617021 (-6050 675);
PAINT SKYBLUE (-6050 675);
FORCEPROP 1 LAST PART_NUMBER C52245-001
J 0
(-6050 625);
DISPLAY 0.617021 (-6050 625);
PAINT BLUE (-6050 625);
FORCEPROP 2 LAST CDS_LIB mstr_discrete
J 0
(-6200 775);
PAINT MONO (-6200 775);
DISPLAY INVISIBLE (-6200 775);
FORCEPROP 0 LAST ROOM PROC_SIDEBAND
J 0
(-6050 925);
DISPLAY 1.021277 (-6050 925);
PAINT ORANGE (-6050 925);
DISPLAY INVISIBLE (-6050 925);
FORCEPROP 1 LAST PATH I330
J 0
(-6050 875);
DISPLAY 0.978723 (-6050 875);
PAINT BLUE (-6050 875);
DISPLAY INVISIBLE (-6050 875);
FORCEPROP 2 LAST CDS_LOCATION Q2T1
J 0
(-6050 825);
DISPLAY 0.617021 (-6050 825);
PAINT AQUA (-6050 825);
DISPLAY INVISIBLE (-6050 825);
FORCEPROP 2 LAST SEC 1
J 0
(-6050 925);
DISPLAY 0.680851 (-6050 925);
PAINT MONO (-6050 925);
DISPLAY INVISIBLE (-6050 925);
FORCEPROP 2 LAST SEC_TYPE SM
J 0
(-6050 925);
DISPLAY 1.021277 (-6050 925);
PAINT ORANGE (-6050 925);
DISPLAY INVISIBLE (-6050 925);
FORCEPROP 0 LAST BOM_COST PROC_SIDEBAND
J 0
(-6050 1025);
DISPLAY 1.021277 (-6050 1025);
PAINT ORANGE (-6050 1025);
DISPLAY INVISIBLE (-6050 1025);
FORCEADD GND..1
(-5500 775);
FORCEPROP 3 LASTPIN (-5500 825) SIG_NAME GND\g
J 0
(-5490 835);
DISPLAY 0.659574 (-5490 835);
PAINT MONO (-5490 835);
DISPLAY INVISIBLE (-5490 835);
FORCEPROP 1 LAST BODY_TYPE PLUMBING
J 0
(-5545 732);
DISPLAY 0.340426 (-5545 732);
PAINT GREEN (-5545 732);
DISPLAY INVISIBLE (-5545 732);
FORCEPROP 1 LAST SIZE 1B
J 0
(-5425 725);
DISPLAY 0.872340 (-5425 725);
PAINT AQUA (-5425 725);
DISPLAY INVISIBLE (-5425 725);
FORCEPROP 1 LAST VOLTAGE 0.0V
J 0
(-5545 732);
DISPLAY 0.340426 (-5545 732);
PAINT SKYBLUE (-5545 732);
DISPLAY INVISIBLE (-5545 732);
FORCEPROP 1 LAST HDL_POWER GND
J 0
(-5500 925);
DISPLAY 0.872340 (-5500 925);
PAINT GREEN (-5500 925);
DISPLAY INVISIBLE (-5500 925);
FORCEPROP 2 LAST CDS_LIB mstr_symbols
J 0
(-5500 775);
PAINT MONO (-5500 775);
DISPLAY INVISIBLE (-5500 775);
FORCEPROP 1 LAST PATH I333
J 0
(-5425 775);
DISPLAY 0.872340 (-5425 775);
PAINT AQUA (-5425 775);
DISPLAY INVISIBLE (-5425 775);
FORCEADD RES..2
(-2275 1525);
FORCEPROP 1 LAST PART_NUMBER G21796-072
J 0
(-2235 1400);
DISPLAY 0.617021 (-2235 1400);
PAINT BLUE (-2235 1400);
FORCEPROP 1 LAST PACK_TYPE 0402
J 0
(-2235 1350);
DISPLAY 0.617021 (-2235 1350);
PAINT SKYBLUE (-2235 1350);
FORCEPROP 1 LAST MATERIAL CHIP
J 0
(-2235 1450);
DISPLAY 0.617021 (-2235 1450);
PAINT SKYBLUE (-2235 1450);
FORCEPROP 1 LAST WATTAGE 1/16W
J 0
(-2235 1500);
DISPLAY 0.617021 (-2235 1500);
PAINT SKYBLUE (-2235 1500);
FORCEPROP 1 LAST TOLERANCE 1%
J 0
(-2230 1550);
DISPLAY 0.617021 (-2230 1550);
PAINT SKYBLUE (-2230 1550);
FORCEPROP 1 LAST VALUE 4.75K
J 0
(-2230 1600);
DISPLAY 0.617021 (-2230 1600);
PAINT SKYBLUE (-2230 1600);
FORCEPROP 1 LAST LOCATION R8D25
J 0
(-2230 1650);
DISPLAY 0.617021 (-2230 1650);
PAINT AQUA (-2230 1650);
FORCEPROP 1 LASTPIN (-2275 1625) $PN 1
J 0
(-2270 1587);
DISPLAY 0.617021 (-2270 1587);
PAINT ORANGE (-2270 1587);
FORCEPROP 1 LASTPIN (-2275 1425) $PN 2
J 0
(-2270 1435);
DISPLAY 0.617021 (-2270 1435);
PAINT ORANGE (-2270 1435);
FORCEPROP 2 LAST CDS_LIB mstr_discrete
J 0
(-2275 1525);
PAINT ORANGE (-2275 1525);
DISPLAY INVISIBLE (-2275 1525);
FORCEPROP 2 LAST CDS_LOCATION R8D25
J 0
(-2230 1650);
DISPLAY 0.617021 (-2230 1650);
PAINT AQUA (-2230 1650);
DISPLAY INVISIBLE (-2230 1650);
FORCEPROP 2 LAST SEC 1
J 0
(-2225 1750);
DISPLAY 0.680851 (-2225 1750);
PAINT MONO (-2225 1750);
DISPLAY INVISIBLE (-2225 1750);
FORCEPROP 1 LAST PATH I335
J 0
(-2225 1700);
DISPLAY 0.978723 (-2225 1700);
PAINT WHITE (-2225 1700);
DISPLAY INVISIBLE (-2225 1700);
FORCEPROP 2 LAST SEC_TYPE 0402
J 0
(-2225 1750);
DISPLAY 1.021277 (-2225 1750);
PAINT ORANGE (-2225 1750);
DISPLAY INVISIBLE (-2225 1750);
FORCEPROP 0 LAST ROOM BMC_MISC
J 0
(-2225 1750);
DISPLAY 1.021277 (-2225 1750);
PAINT ORANGE (-2225 1750);
DISPLAY INVISIBLE (-2225 1750);
FORCEPROP 0 LAST BOM_COST SM_CONTROLLER
J 0
(-2225 1850);
DISPLAY 1.021277 (-2225 1850);
PAINT ORANGE (-2225 1850);
DISPLAY INVISIBLE (-2225 1850);
FORCEADD P3V3_STBY..1
(-2275 1725);
FORCEPROP 3 LASTPIN (-2275 1675) SIG_NAME P3V3_STBY\g
J 0
(-2265 1685);
DISPLAY 0.659574 (-2265 1685);
PAINT MONO (-2265 1685);
DISPLAY INVISIBLE (-2265 1685);
FORCEPROP 1 LAST HDL_POWER P3V3_STBY
J 0
(-2575 1600);
DISPLAY 0.872340 (-2575 1600);
PAINT ORANGE (-2575 1600);
DISPLAY INVISIBLE (-2575 1600);
FORCEPROP 1 LAST VOLTAGE 3.3V
J 0
(-2320 1682);
DISPLAY 0.340426 (-2320 1682);
PAINT SKYBLUE (-2320 1682);
DISPLAY INVISIBLE (-2320 1682);
FORCEPROP 1 LAST BODY_TYPE PLUMBING
J 0
(-2320 1682);
DISPLAY 0.340426 (-2320 1682);
PAINT GREEN (-2320 1682);
DISPLAY INVISIBLE (-2320 1682);
FORCEPROP 1 LAST PATH I339
J 0
(-2230 1727);
DISPLAY 0.340426 (-2230 1727);
PAINT GREEN (-2230 1727);
DISPLAY INVISIBLE (-2230 1727);
FORCEPROP 2 LAST CDS_LIB mstr_symbols
J 0
(-2275 1725);
PAINT MONO (-2275 1725);
DISPLAY INVISIBLE (-2275 1725);
FORCEPROP 1 LAST SIZE 1B
J 0
(-2230 1747);
DISPLAY 0.340426 (-2230 1747);
PAINT GREEN (-2230 1747);
DISPLAY INVISIBLE (-2230 1747);
FORCEADD FET_N..8
(-5500 1100);
FORCEPROP 1 LASTPIN (-5500 900) $PN 2
J 2
(-5442 900);
DISPLAY 0.617021 (-5442 900);
PAINT WHITE (-5442 900);
FORCEPROP 1 LASTPIN (-5700 1000) $PN 1
J 2
(-5697 1015);
DISPLAY 0.617021 (-5697 1015);
PAINT WHITE (-5697 1015);
FORCEPROP 1 LAST MATERIAL FET
J 0
(-5300 1000);
DISPLAY 0.617021 (-5300 1000);
PAINT SKYBLUE (-5300 1000);
FORCEPROP 1 LASTPIN (-5500 1300) $PN 3
J 2
(-5447 1265);
DISPLAY 0.617021 (-5447 1265);
PAINT WHITE (-5447 1265);
FORCEPROP 1 LAST VALUE 2N7002
J 0
(-5300 1050);
DISPLAY 0.617021 (-5300 1050);
PAINT SKYBLUE (-5300 1050);
FORCEPROP 1 LAST LOCATION Q2T2
J 0
(-5300 1100);
DISPLAY 0.617021 (-5300 1100);
PAINT AQUA (-5300 1100);
FORCEPROP 1 LAST PART_NUMBER C79254-001
J 0
(-5300 900);
DISPLAY 0.617021 (-5300 900);
PAINT BLUE (-5300 900);
FORCEPROP 1 LAST PACK_TYPE SOT23LF
J 0
(-5300 950);
DISPLAY 0.978723 (-5300 950);
PAINT SKYBLUE (-5300 950);
DISPLAY INVISIBLE (-5300 950);
FORCEPROP 2 LAST CDS_LIB mstr_discrete
J 0
(-5500 1100);
PAINT MONO (-5500 1100);
DISPLAY INVISIBLE (-5500 1100);
FORCEPROP 0 LAST ROOM PROC_SIDEBAND
J 0
(-5300 1200);
DISPLAY 1.021277 (-5300 1200);
PAINT ORANGE (-5300 1200);
DISPLAY INVISIBLE (-5300 1200);
FORCEPROP 1 LAST PATH I340
J 0
(-5300 1150);
DISPLAY 0.978723 (-5300 1150);
PAINT BLUE (-5300 1150);
DISPLAY INVISIBLE (-5300 1150);
FORCEPROP 2 LAST CDS_LOCATION Q2T2
J 0
(-5300 1100);
DISPLAY 0.617021 (-5300 1100);
PAINT AQUA (-5300 1100);
DISPLAY INVISIBLE (-5300 1100);
FORCEPROP 2 LAST SEC 1
J 0
(-5300 1200);
DISPLAY 0.680851 (-5300 1200);
PAINT MONO (-5300 1200);
DISPLAY INVISIBLE (-5300 1200);
FORCEPROP 0 LAST BOM_COST PROC_SIDEBAND
J 0
(-5300 1300);
DISPLAY 1.021277 (-5300 1300);
PAINT ORANGE (-5300 1300);
DISPLAY INVISIBLE (-5300 1300);
FORCEPROP 2 LAST SEC_TYPE SOT23LF
J 0
(-5300 1200);
DISPLAY 1.021277 (-5300 1200);
PAINT ORANGE (-5300 1200);
DISPLAY INVISIBLE (-5300 1200);
FORCEADD RES..1
(-7175 3100);
FORCEPROP 1 LAST MATERIAL CHIP
J 0
(-6925 3000);
DISPLAY 0.617021 (-6925 3000);
PAINT SKYBLUE (-6925 3000);
FORCEPROP 1 LAST PART_NUMBER G21796-072
J 0
(-7400 3000);
DISPLAY 0.617021 (-7400 3000);
PAINT BLUE (-7400 3000);
FORCEPROP 1 LAST VALUE 4.75K
J 2
(-7200 3050);
DISPLAY 0.617021 (-7200 3050);
PAINT SKYBLUE (-7200 3050);
FORCEPROP 1 LAST TOLERANCE 1%
J 0
(-7125 3050);
DISPLAY 0.617021 (-7125 3050);
PAINT SKYBLUE (-7125 3050);
FORCEPROP 1 LASTPIN (-7075 3100) $PN 2
J 0
(-7113 3112);
DISPLAY 0.617021 (-7113 3112);
PAINT ORANGE (-7113 3112);
FORCEPROP 1 LAST PACK_TYPE 0402
J 0
(-7000 3050);
DISPLAY 0.617021 (-7000 3050);
PAINT SKYBLUE (-7000 3050);
FORCEPROP 1 LAST WATTAGE 1/16W
J 2
(-6750 3050);
DISPLAY 0.617021 (-6750 3050);
PAINT SKYBLUE (-6750 3050);
FORCEPROP 1 LAST LOCATION R3N12
J 0
(-7225 3150);
DISPLAY 0.617021 (-7225 3150);
PAINT AQUA (-7225 3150);
FORCEPROP 1 LASTPIN (-7275 3100) $PN 1
J 0
(-7263 3112);
DISPLAY 0.617021 (-7263 3112);
PAINT ORANGE (-7263 3112);
FORCEPROP 2 LAST SEC_TYPE 0402
J 0
(-7225 3300);
DISPLAY 1.021277 (-7225 3300);
PAINT ORANGE (-7225 3300);
DISPLAY INVISIBLE (-7225 3300);
FORCEPROP 2 LAST SEC 1
J 0
(-7225 3300);
PAINT MONO (-7225 3300);
DISPLAY INVISIBLE (-7225 3300);
FORCEPROP 2 LAST BOM_COST SM_CONTROLLER
J 0
(-7225 3250);
DISPLAY 1.021277 (-7225 3250);
PAINT ORANGE (-7225 3250);
DISPLAY INVISIBLE (-7225 3250);
FORCEPROP 2 LAST CDS_LIB mstr_discrete
J 0
(-7175 3100);
PAINT ORANGE (-7175 3100);
DISPLAY INVISIBLE (-7175 3100);
FORCEPROP 2 LAST CDS_LOCATION R3N12
J 0
(-7225 3150);
DISPLAY 0.617021 (-7225 3150);
PAINT AQUA (-7225 3150);
DISPLAY INVISIBLE (-7225 3150);
FORCEPROP 1 LAST PATH I342
J 0
(-7225 3250);
DISPLAY 0.978723 (-7225 3250);
PAINT WHITE (-7225 3250);
DISPLAY INVISIBLE (-7225 3250);
FORCEPROP 2 LAST ROOM BMC_MISC
J 0
(-7225 3200);
DISPLAY 1.021277 (-7225 3200);
PAINT ORANGE (-7225 3200);
DISPLAY INVISIBLE (-7225 3200);
FORCEADD OFFPAGE..2
(-5950 3100);
FORCEPROP 2 LAST $XR3 190 
J 0
(-5401 3100);
DISPLAY 0.638298 (-5401 3100);
PAINT MONO (-5401 3100);
FORCEPROP 2 LAST $XR2 144 
J 0
(-5521 3100);
DISPLAY 0.638298 (-5521 3100);
PAINT MONO (-5521 3100);
FORCEPROP 2 LAST $XR1 120 
J 0
(-5641 3100);
DISPLAY 0.638298 (-5641 3100);
PAINT MONO (-5641 3100);
FORCEPROP 2 LAST $XR0 181 
J 0
(-5761 3100);
DISPLAY 0.638298 (-5761 3100);
PAINT MONO (-5761 3100);
FORCEPROP 2 LAST PATH I343
J 0
(-5775 3175);
DISPLAY 1.021277 (-5775 3175);
PAINT ORANGE (-5775 3175);
DISPLAY INVISIBLE (-5775 3175);
FORCEPROP 2 LAST CDS_LIB mstr_standard
J 0
(-5950 3100);
PAINT MONO (-5950 3100);
DISPLAY INVISIBLE (-5950 3100);
FORCEPROP 1 LAST OFFPAGE TRUE
J 0
(-5625 2975);
DISPLAY 0.872340 (-5625 2975);
PAINT GREEN (-5625 2975);
DISPLAY INVISIBLE (-5625 2975);
FORCEPROP 1 LAST COMMENT_BODY TRUE
J 0
(-5995 3005);
DISPLAY 0.872340 (-5995 3005);
PAINT GREEN (-5995 3005);
DISPLAY INVISIBLE (-5995 3005);
FORCEADD RES..1
(-7175 2875);
FORCEPROP 1 LAST MATERIAL CHIP
J 0
(-6925 2775);
DISPLAY 0.617021 (-6925 2775);
PAINT SKYBLUE (-6925 2775);
FORCEPROP 1 LAST PACK_TYPE 0402
J 0
(-7000 2825);
DISPLAY 0.617021 (-7000 2825);
PAINT SKYBLUE (-7000 2825);
FORCEPROP 1 LAST TOLERANCE 1%
J 0
(-7125 2825);
DISPLAY 0.617021 (-7125 2825);
PAINT SKYBLUE (-7125 2825);
FORCEPROP 1 LAST PART_NUMBER G21796-072
J 0
(-7400 2775);
DISPLAY 0.617021 (-7400 2775);
PAINT BLUE (-7400 2775);
FORCEPROP 1 LAST VALUE 4.75K
J 2
(-7200 2825);
DISPLAY 0.617021 (-7200 2825);
PAINT SKYBLUE (-7200 2825);
FORCEPROP 1 LAST WATTAGE 1/16W
J 2
(-6750 2825);
DISPLAY 0.617021 (-6750 2825);
PAINT SKYBLUE (-6750 2825);
FORCEPROP 1 LASTPIN (-7075 2875) $PN 2
J 0
(-7113 2887);
DISPLAY 0.617021 (-7113 2887);
PAINT ORANGE (-7113 2887);
FORCEPROP 1 LAST LOCATION R3N11
J 0
(-7225 2925);
DISPLAY 0.617021 (-7225 2925);
PAINT AQUA (-7225 2925);
FORCEPROP 1 LASTPIN (-7275 2875) $PN 1
J 0
(-7263 2887);
DISPLAY 0.617021 (-7263 2887);
PAINT ORANGE (-7263 2887);
FORCEPROP 2 LAST SEC_TYPE 0402
J 0
(-7225 3075);
DISPLAY 1.021277 (-7225 3075);
PAINT ORANGE (-7225 3075);
DISPLAY INVISIBLE (-7225 3075);
FORCEPROP 2 LAST SEC 1
J 0
(-7225 3075);
PAINT MONO (-7225 3075);
DISPLAY INVISIBLE (-7225 3075);
FORCEPROP 2 LAST CDS_LIB mstr_discrete
J 0
(-7175 2875);
PAINT ORANGE (-7175 2875);
DISPLAY INVISIBLE (-7175 2875);
FORCEPROP 2 LAST BOM_COST SM_CONTROLLER
J 0
(-7225 3025);
DISPLAY 1.021277 (-7225 3025);
PAINT ORANGE (-7225 3025);
DISPLAY INVISIBLE (-7225 3025);
FORCEPROP 2 LAST CDS_LOCATION R3N11
J 0
(-7225 2925);
DISPLAY 0.617021 (-7225 2925);
PAINT AQUA (-7225 2925);
DISPLAY INVISIBLE (-7225 2925);
FORCEPROP 1 LAST PATH I344
J 0
(-7225 3025);
DISPLAY 0.978723 (-7225 3025);
PAINT WHITE (-7225 3025);
DISPLAY INVISIBLE (-7225 3025);
FORCEPROP 2 LAST ROOM BMC_MISC
J 0
(-7225 2975);
DISPLAY 1.021277 (-7225 2975);
PAINT ORANGE (-7225 2975);
DISPLAY INVISIBLE (-7225 2975);
FORCEADD OFFPAGE..2
(-5950 2875);
FORCEPROP 2 LAST $XR2 120 
J 0
(-5521 2875);
DISPLAY 0.638298 (-5521 2875);
PAINT MONO (-5521 2875);
FORCEPROP 2 LAST $XR1 181 
J 0
(-5641 2875);
DISPLAY 0.638298 (-5641 2875);
PAINT MONO (-5641 2875);
FORCEPROP 2 LAST $XR0 146 
J 0
(-5761 2875);
DISPLAY 0.638298 (-5761 2875);
PAINT MONO (-5761 2875);
FORCEPROP 1 LAST OFFPAGE TRUE
J 0
(-5625 2750);
DISPLAY 0.872340 (-5625 2750);
PAINT GREEN (-5625 2750);
DISPLAY INVISIBLE (-5625 2750);
FORCEPROP 2 LAST PATH I345
J 0
(-5775 2950);
DISPLAY 1.021277 (-5775 2950);
PAINT ORANGE (-5775 2950);
DISPLAY INVISIBLE (-5775 2950);
FORCEPROP 2 LAST CDS_LIB mstr_standard
J 0
(-5950 2875);
PAINT MONO (-5950 2875);
DISPLAY INVISIBLE (-5950 2875);
FORCEPROP 1 LAST COMMENT_BODY TRUE
J 0
(-5995 2780);
DISPLAY 0.872340 (-5995 2780);
PAINT GREEN (-5995 2780);
DISPLAY INVISIBLE (-5995 2780);
FORCEADD RES..1
(-7175 2650);
FORCEPROP 1 LAST LOCATION R2M2
J 0
(-7225 2700);
DISPLAY 0.617021 (-7225 2700);
PAINT AQUA (-7225 2700);
FORCEPROP 1 LAST MATERIAL CHIP
J 0
(-6925 2550);
DISPLAY 0.617021 (-6925 2550);
PAINT SKYBLUE (-6925 2550);
FORCEPROP 1 LAST PACK_TYPE 0402
J 0
(-7000 2600);
DISPLAY 0.617021 (-7000 2600);
PAINT SKYBLUE (-7000 2600);
FORCEPROP 1 LAST TOLERANCE 1%
J 0
(-7125 2600);
DISPLAY 0.617021 (-7125 2600);
PAINT SKYBLUE (-7125 2600);
FORCEPROP 1 LAST PART_NUMBER G21796-072
J 0
(-7400 2550);
DISPLAY 0.617021 (-7400 2550);
PAINT BLUE (-7400 2550);
FORCEPROP 1 LAST VALUE 4.75K
J 2
(-7200 2600);
DISPLAY 0.617021 (-7200 2600);
PAINT SKYBLUE (-7200 2600);
FORCEPROP 1 LAST WATTAGE 1/16W
J 2
(-6750 2600);
DISPLAY 0.617021 (-6750 2600);
PAINT SKYBLUE (-6750 2600);
FORCEPROP 1 LASTPIN (-7075 2650) $PN 2
J 0
(-7113 2662);
DISPLAY 0.617021 (-7113 2662);
PAINT ORANGE (-7113 2662);
FORCEPROP 1 LASTPIN (-7275 2650) $PN 1
J 0
(-7263 2662);
DISPLAY 0.617021 (-7263 2662);
PAINT ORANGE (-7263 2662);
FORCEPROP 2 LAST SEC_TYPE 0402
J 0
(-7225 2850);
DISPLAY 1.021277 (-7225 2850);
PAINT ORANGE (-7225 2850);
DISPLAY INVISIBLE (-7225 2850);
FORCEPROP 2 LAST SEC 1
J 0
(-7225 2850);
PAINT MONO (-7225 2850);
DISPLAY INVISIBLE (-7225 2850);
FORCEPROP 2 LAST BOM_COST SM_CONTROLLER
J 0
(-7225 2800);
DISPLAY 1.021277 (-7225 2800);
PAINT ORANGE (-7225 2800);
DISPLAY INVISIBLE (-7225 2800);
FORCEPROP 1 LAST PATH I346
J 0
(-7225 2800);
DISPLAY 0.978723 (-7225 2800);
PAINT WHITE (-7225 2800);
DISPLAY INVISIBLE (-7225 2800);
FORCEPROP 2 LAST CDS_LIB mstr_discrete
J 0
(-7175 2650);
PAINT ORANGE (-7175 2650);
DISPLAY INVISIBLE (-7175 2650);
FORCEPROP 2 LAST CDS_LOCATION R2M2
J 0
(-7225 2700);
DISPLAY 0.617021 (-7225 2700);
PAINT AQUA (-7225 2700);
DISPLAY INVISIBLE (-7225 2700);
FORCEPROP 2 LAST ROOM BMC_MISC
J 0
(-7225 2750);
DISPLAY 1.021277 (-7225 2750);
PAINT ORANGE (-7225 2750);
DISPLAY INVISIBLE (-7225 2750);
FORCEADD OFFPAGE..2
(-5950 2650);
FORCEPROP 2 LAST $XR3 120 
J 0
(-5431 2650);
DISPLAY 0.638298 (-5431 2650);
PAINT MONO (-5431 2650);
FORCEPROP 2 LAST $XR2 191 
J 0
(-5551 2650);
DISPLAY 0.638298 (-5551 2650);
PAINT MONO (-5551 2650);
FORCEPROP 2 LAST $XR1 156 
J 0
(-5671 2650);
DISPLAY 0.638298 (-5671 2650);
PAINT MONO (-5671 2650);
FORCEPROP 2 LAST $XR0 89 
J 0
(-5761 2650);
DISPLAY 0.638298 (-5761 2650);
PAINT MONO (-5761 2650);
FORCEPROP 2 LAST PATH I347
J 0
(-5500 2700);
DISPLAY 1.021277 (-5500 2700);
PAINT ORANGE (-5500 2700);
DISPLAY INVISIBLE (-5500 2700);
FORCEPROP 1 LAST OFFPAGE TRUE
J 0
(-5625 2525);
DISPLAY 0.872340 (-5625 2525);
PAINT GREEN (-5625 2525);
DISPLAY INVISIBLE (-5625 2525);
FORCEPROP 2 LAST CDS_LIB mstr_standard
J 0
(-5950 2650);
PAINT MONO (-5950 2650);
DISPLAY INVISIBLE (-5950 2650);
FORCEPROP 1 LAST COMMENT_BODY TRUE
J 0
(-5995 2555);
DISPLAY 0.872340 (-5995 2555);
PAINT GREEN (-5995 2555);
DISPLAY INVISIBLE (-5995 2555);
FORCEADD RES..1
(-7175 2425);
FORCEPROP 1 LAST WATTAGE 1/16W
J 2
(-6750 2375);
DISPLAY 0.617021 (-6750 2375);
PAINT SKYBLUE (-6750 2375);
FORCEPROP 1 LAST MATERIAL CHIP
J 0
(-6925 2325);
DISPLAY 0.617021 (-6925 2325);
PAINT SKYBLUE (-6925 2325);
FORCEPROP 1 LAST PACK_TYPE 0402
J 0
(-7000 2375);
DISPLAY 0.617021 (-7000 2375);
PAINT SKYBLUE (-7000 2375);
FORCEPROP 1 LAST TOLERANCE 1%
J 0
(-7125 2375);
DISPLAY 0.617021 (-7125 2375);
PAINT SKYBLUE (-7125 2375);
FORCEPROP 1 LAST VALUE 4.75K
J 2
(-7200 2375);
DISPLAY 0.617021 (-7200 2375);
PAINT SKYBLUE (-7200 2375);
FORCEPROP 1 LASTPIN (-7075 2425) $PN 2
J 0
(-7113 2437);
DISPLAY 0.617021 (-7113 2437);
PAINT ORANGE (-7113 2437);
FORCEPROP 1 LAST LOCATION R2M5
J 0
(-7225 2475);
DISPLAY 0.617021 (-7225 2475);
PAINT AQUA (-7225 2475);
FORCEPROP 1 LAST PART_NUMBER G21796-072
J 0
(-7400 2325);
DISPLAY 0.617021 (-7400 2325);
PAINT BLUE (-7400 2325);
FORCEPROP 1 LASTPIN (-7275 2425) $PN 1
J 0
(-7263 2437);
DISPLAY 0.617021 (-7263 2437);
PAINT ORANGE (-7263 2437);
FORCEPROP 2 LAST SEC 1
J 0
(-7225 2625);
PAINT MONO (-7225 2625);
DISPLAY INVISIBLE (-7225 2625);
FORCEPROP 1 LAST PATH I348
J 0
(-7225 2575);
DISPLAY 0.978723 (-7225 2575);
PAINT WHITE (-7225 2575);
DISPLAY INVISIBLE (-7225 2575);
FORCEPROP 2 LAST SEC_TYPE 0402
J 0
(-7225 2625);
DISPLAY 1.021277 (-7225 2625);
PAINT ORANGE (-7225 2625);
DISPLAY INVISIBLE (-7225 2625);
FORCEPROP 2 LAST BOM_COST SM_CONTROLLER
J 0
(-7225 2575);
DISPLAY 1.021277 (-7225 2575);
PAINT ORANGE (-7225 2575);
DISPLAY INVISIBLE (-7225 2575);
FORCEPROP 2 LAST ROOM BMC_MISC
J 0
(-7225 2525);
DISPLAY 1.021277 (-7225 2525);
PAINT ORANGE (-7225 2525);
DISPLAY INVISIBLE (-7225 2525);
FORCEPROP 2 LAST CDS_LIB mstr_discrete
J 0
(-7175 2425);
PAINT ORANGE (-7175 2425);
DISPLAY INVISIBLE (-7175 2425);
FORCEPROP 2 LAST CDS_LOCATION R2M5
J 0
(-7225 2475);
DISPLAY 0.617021 (-7225 2475);
PAINT AQUA (-7225 2475);
DISPLAY INVISIBLE (-7225 2475);
FORCEADD OFFPAGE..2
(-5950 2425);
FORCEPROP 2 LAST $XR2 190 
J 0
(-5521 2425);
DISPLAY 0.638298 (-5521 2425);
PAINT MONO (-5521 2425);
FORCEPROP 2 LAST $XR1 146 
J 0
(-5641 2425);
DISPLAY 0.638298 (-5641 2425);
PAINT MONO (-5641 2425);
FORCEPROP 2 LAST $XR0 119 
J 0
(-5761 2425);
DISPLAY 0.638298 (-5761 2425);
PAINT MONO (-5761 2425);
FORCEPROP 2 LAST PATH I349
J 0
(-5325 2475);
DISPLAY 1.021277 (-5325 2475);
PAINT ORANGE (-5325 2475);
DISPLAY INVISIBLE (-5325 2475);
FORCEPROP 1 LAST OFFPAGE TRUE
J 0
(-5625 2300);
DISPLAY 0.872340 (-5625 2300);
PAINT GREEN (-5625 2300);
DISPLAY INVISIBLE (-5625 2300);
FORCEPROP 1 LAST COMMENT_BODY TRUE
J 0
(-5995 2330);
DISPLAY 0.872340 (-5995 2330);
PAINT GREEN (-5995 2330);
DISPLAY INVISIBLE (-5995 2330);
FORCEPROP 2 LAST CDS_LIB mstr_standard
J 0
(-5950 2425);
PAINT MONO (-5950 2425);
DISPLAY INVISIBLE (-5950 2425);
FORCEADD SWITCH_D90553001..1
(-4525 2675);
FORCEPROP 1 LAST PART_NAME SWITCH_D90553001
J 0
(-4775 2525);
DISPLAY 0.744681 (-4775 2525);
PAINT GREEN (-4775 2525);
FORCEPROP 1 LAST PART_NUMBER D90553-001
J 0
(-4775 2575);
DISPLAY 0.617021 (-4775 2575);
PAINT BLUE (-4775 2575);
FORCEPROP 1 LASTPIN (-4775 2675) $PN 1
J 0
(-4738 2688);
DISPLAY 0.617021 (-4738 2688);
PAINT ORANGE (-4738 2688);
FORCEPROP 1 LASTPIN (-4275 2675) $PN 2
J 0
(-4350 2688);
DISPLAY 0.617021 (-4350 2688);
PAINT ORANGE (-4350 2688);
FORCEPROP 1 LAST MATERIAL IC
J 0
(-4625 2875);
DISPLAY 0.617021 (-4625 2875);
PAINT SKYBLUE (-4625 2875);
FORCEPROP 1 LAST LOCATION S8E1
J 0
(-4625 2925);
DISPLAY 0.617021 (-4625 2925);
PAINT AQUA (-4625 2925);
FORCEPROP 2 LAST CDS_LIB mstr_misc
J 0
(-4525 2675);
PAINT MONO (-4525 2675);
DISPLAY INVISIBLE (-4525 2675);
FORCEPROP 1 LAST PATH I351
J 0
(-4425 2875);
DISPLAY 0.744681 (-4425 2875);
PAINT GREEN (-4425 2875);
DISPLAY INVISIBLE (-4425 2875);
FORCEPROP 0 LAST ROOM MIO_CHASSIS
J 0
(-4625 3025);
DISPLAY 1.021277 (-4625 3025);
PAINT ORANGE (-4625 3025);
DISPLAY INVISIBLE (-4625 3025);
FORCEPROP 2 LAST CDS_LOCATION S8E1
J 0
(-4625 2925);
DISPLAY 0.617021 (-4625 2925);
PAINT AQUA (-4625 2925);
DISPLAY INVISIBLE (-4625 2925);
FORCEPROP 2 LAST SEC 1
J 0
(-4625 2975);
DISPLAY 0.680851 (-4625 2975);
PAINT MONO (-4625 2975);
DISPLAY INVISIBLE (-4625 2975);
FORCEPROP 2 LAST SEC_TYPE SMLF
J 0
(-4625 2975);
DISPLAY 1.021277 (-4625 2975);
PAINT ORANGE (-4625 2975);
DISPLAY INVISIBLE (-4625 2975);
FORCEPROP 0 LAST BOM_COST MIO_CHASSIS
J 0
(-4625 3125);
DISPLAY 1.021277 (-4625 3125);
PAINT ORANGE (-4625 3125);
DISPLAY INVISIBLE (-4625 3125);
FORCEPROP 1 LAST PACK_TYPE SMLF
J 0
(-4625 2975);
DISPLAY 0.744681 (-4625 2975);
PAINT SKYBLUE (-4625 2975);
DISPLAY INVISIBLE (-4625 2975);
FORCEADD RES..1
(-3675 2675);
FORCEPROP 1 LAST LOCATION R2R9
J 0
(-3725 2725);
DISPLAY 0.617021 (-3725 2725);
PAINT AQUA (-3725 2725);
FORCEPROP 1 LAST PACK_TYPE 0402
J 0
(-3800 2475);
DISPLAY 0.617021 (-3800 2475);
PAINT SKYBLUE (-3800 2475);
FORCEPROP 1 LAST WATTAGE 1/16W
J 2
(-3700 2525);
DISPLAY 0.617021 (-3700 2525);
PAINT SKYBLUE (-3700 2525);
FORCEPROP 1 LAST MATERIAL CHIP
J 0
(-3675 2525);
DISPLAY 0.617021 (-3675 2525);
PAINT SKYBLUE (-3675 2525);
FORCEPROP 1 LAST VALUE 200.0
J 2
(-3700 2575);
DISPLAY 0.617021 (-3700 2575);
PAINT SKYBLUE (-3700 2575);
FORCEPROP 1 LAST TOLERANCE 1%
J 0
(-3675 2575);
DISPLAY 0.617021 (-3675 2575);
PAINT SKYBLUE (-3675 2575);
FORCEPROP 1 LASTPIN (-3575 2675) $PN 2
J 0
(-3613 2687);
DISPLAY 0.617021 (-3613 2687);
PAINT ORANGE (-3613 2687);
FORCEPROP 1 LASTPIN (-3775 2675) $PN 1
J 0
(-3763 2687);
DISPLAY 0.617021 (-3763 2687);
PAINT ORANGE (-3763 2687);
FORCEPROP 1 LAST PART_NUMBER G21796-004
J 0
(-3725 2775);
DISPLAY 0.617021 (-3725 2775);
PAINT BLUE (-3725 2775);
FORCEPROP 2 LAST SEC_TYPE 0402
J 0
(-3725 2875);
DISPLAY 1.021277 (-3725 2875);
PAINT ORANGE (-3725 2875);
DISPLAY INVISIBLE (-3725 2875);
FORCEPROP 0 LAST BOM_COST MIO_CHASSIS
J 0
(-3725 2975);
DISPLAY 1.021277 (-3725 2975);
PAINT ORANGE (-3725 2975);
DISPLAY INVISIBLE (-3725 2975);
FORCEPROP 2 LAST SEC 1
J 0
(-3725 2875);
DISPLAY 0.680851 (-3725 2875);
PAINT MONO (-3725 2875);
DISPLAY INVISIBLE (-3725 2875);
FORCEPROP 0 LAST ROOM MIO_CHASSIS
J 0
(-3725 2875);
DISPLAY 1.021277 (-3725 2875);
PAINT ORANGE (-3725 2875);
DISPLAY INVISIBLE (-3725 2875);
FORCEPROP 1 LAST PATH I352
J 0
(-3725 2825);
DISPLAY 0.978723 (-3725 2825);
PAINT WHITE (-3725 2825);
DISPLAY INVISIBLE (-3725 2825);
FORCEPROP 2 LAST CDS_LOCATION R2R9
J 0
(-3725 2725);
DISPLAY 0.617021 (-3725 2725);
PAINT AQUA (-3725 2725);
DISPLAY INVISIBLE (-3725 2725);
FORCEPROP 2 LAST CDS_LIB mstr_discrete
J 0
(-3675 2675);
PAINT MONO (-3675 2675);
DISPLAY INVISIBLE (-3675 2675);
FORCEADD CAP_A..1
(-3225 2450);
FORCEPROP 1 LAST PACK_TYPE 0402V
J 0
(-3175 2250);
DISPLAY 0.617021 (-3175 2250);
PAINT SKYBLUE (-3175 2250);
FORCEPROP 1 LAST PART_NUMBER D97712-004
J 0
(-3175 2300);
DISPLAY 0.617021 (-3175 2300);
PAINT BLUE (-3175 2300);
FORCEPROP 1 LAST MATERIAL X6S
J 0
(-3175 2350);
DISPLAY 0.617021 (-3175 2350);
PAINT SKYBLUE (-3175 2350);
FORCEPROP 1 LAST TOLERANCE 10%
J 0
(-3175 2400);
DISPLAY 0.617021 (-3175 2400);
PAINT SKYBLUE (-3175 2400);
FORCEPROP 1 LAST VOLTAGE 6.3V
J 0
(-3175 2450);
DISPLAY 0.617021 (-3175 2450);
PAINT SKYBLUE (-3175 2450);
FORCEPROP 1 LAST VALUE 1.0UF
J 0
(-3175 2500);
DISPLAY 0.617021 (-3175 2500);
PAINT SKYBLUE (-3175 2500);
FORCEPROP 1 LAST LOCATION C2R12
J 0
(-3175 2550);
DISPLAY 0.617021 (-3175 2550);
PAINT AQUA (-3175 2550);
FORCEPROP 1 LASTPIN (-3225 2550) $PN 1
J 0
(-3215 2530);
DISPLAY 0.617021 (-3215 2530);
PAINT ORANGE (-3215 2530);
FORCEPROP 1 LASTPIN (-3225 2350) $PN 2
J 0
(-3215 2330);
DISPLAY 0.617021 (-3215 2330);
PAINT ORANGE (-3215 2330);
FORCEPROP 0 LAST ROOM MIO_CHASSIS
J 0
(-3175 2650);
DISPLAY 1.021277 (-3175 2650);
PAINT ORANGE (-3175 2650);
DISPLAY INVISIBLE (-3175 2650);
FORCEPROP 2 LAST SEC 1
J 0
(-3175 2650);
DISPLAY 0.680851 (-3175 2650);
PAINT MONO (-3175 2650);
DISPLAY INVISIBLE (-3175 2650);
FORCEPROP 2 LAST SEC_TYPE 0402V
J 0
(-3175 2650);
DISPLAY 1.021277 (-3175 2650);
PAINT ORANGE (-3175 2650);
DISPLAY INVISIBLE (-3175 2650);
FORCEPROP 0 LAST BOM_COST MIO_CHASSIS
J 0
(-3175 2750);
DISPLAY 1.021277 (-3175 2750);
PAINT ORANGE (-3175 2750);
DISPLAY INVISIBLE (-3175 2750);
FORCEPROP 1 LAST PATH I353
J 0
(-3175 2600);
DISPLAY 0.978723 (-3175 2600);
PAINT WHITE (-3175 2600);
DISPLAY INVISIBLE (-3175 2600);
FORCEPROP 2 LAST CDS_SEC 1
J 0
(-3175 2600);
PAINT ORANGE (-3175 2600);
DISPLAY INVISIBLE (-3175 2600);
FORCEPROP 2 LAST CDS_LIB dev_discrete
J 0
(-3225 2450);
PAINT ORANGE (-3225 2450);
DISPLAY INVISIBLE (-3225 2450);
FORCEPROP 2 LAST CDS_LOCATION C2R12
J 0
(-3175 2550);
DISPLAY 0.617021 (-3175 2550);
PAINT AQUA (-3175 2550);
DISPLAY INVISIBLE (-3175 2550);
FORCEADD GND..1
(-3225 2175);
FORCEPROP 3 LASTPIN (-3225 2225) SIG_NAME GND\g
J 0
(-3215 2235);
DISPLAY 0.659574 (-3215 2235);
PAINT MONO (-3215 2235);
DISPLAY INVISIBLE (-3215 2235);
FORCEPROP 1 LAST HDL_POWER GND
J 0
(-3225 2325);
DISPLAY 0.872340 (-3225 2325);
PAINT GREEN (-3225 2325);
DISPLAY INVISIBLE (-3225 2325);
FORCEPROP 1 LAST VOLTAGE 0.0V
J 0
(-3270 2132);
DISPLAY 0.340426 (-3270 2132);
PAINT SKYBLUE (-3270 2132);
DISPLAY INVISIBLE (-3270 2132);
FORCEPROP 1 LAST SIZE 1B
J 0
(-3150 2125);
DISPLAY 0.872340 (-3150 2125);
PAINT AQUA (-3150 2125);
DISPLAY INVISIBLE (-3150 2125);
FORCEPROP 2 LAST CDS_LIB mstr_symbols
J 0
(-3225 2175);
PAINT MONO (-3225 2175);
DISPLAY INVISIBLE (-3225 2175);
FORCEPROP 1 LAST BODY_TYPE PLUMBING
J 0
(-3270 2132);
DISPLAY 0.340426 (-3270 2132);
PAINT GREEN (-3270 2132);
DISPLAY INVISIBLE (-3270 2132);
FORCEPROP 1 LAST PATH I354
J 0
(-3150 2175);
DISPLAY 0.872340 (-3150 2175);
PAINT AQUA (-3150 2175);
DISPLAY INVISIBLE (-3150 2175);
FORCEADD GND..1
(-4925 2500);
FORCEPROP 3 LASTPIN (-4925 2550) SIG_NAME GND\g
J 0
(-4915 2560);
DISPLAY 0.659574 (-4915 2560);
PAINT MONO (-4915 2560);
DISPLAY INVISIBLE (-4915 2560);
FORCEPROP 1 LAST VOLTAGE 0.0V
J 0
(-4970 2457);
DISPLAY 0.340426 (-4970 2457);
PAINT SKYBLUE (-4970 2457);
DISPLAY INVISIBLE (-4970 2457);
FORCEPROP 2 LAST CDS_LIB mstr_symbols
J 0
(-4925 2500);
PAINT MONO (-4925 2500);
DISPLAY INVISIBLE (-4925 2500);
FORCEPROP 1 LAST SIZE 1B
J 0
(-4850 2450);
DISPLAY 0.872340 (-4850 2450);
PAINT AQUA (-4850 2450);
DISPLAY INVISIBLE (-4850 2450);
FORCEPROP 1 LAST BODY_TYPE PLUMBING
J 0
(-4970 2457);
DISPLAY 0.340426 (-4970 2457);
PAINT GREEN (-4970 2457);
DISPLAY INVISIBLE (-4970 2457);
FORCEPROP 1 LAST PATH I355
J 0
(-4850 2500);
DISPLAY 0.872340 (-4850 2500);
PAINT AQUA (-4850 2500);
DISPLAY INVISIBLE (-4850 2500);
FORCEPROP 1 LAST HDL_POWER GND
J 0
(-4925 2650);
DISPLAY 0.872340 (-4925 2650);
PAINT GREEN (-4925 2650);
DISPLAY INVISIBLE (-4925 2650);
FORCEADD OFFPAGE..2
(-600 2925);
FORCEPROP 2 LAST $XR2 145 
J 0
(-411 2961);
DISPLAY 0.638298 (-411 2961);
PAINT MONO (-411 2961);
FORCEPROP 2 LAST $XR1 119 
J 0
(-411 2889);
DISPLAY 0.638298 (-411 2889);
PAINT MONO (-411 2889);
FORCEPROP 2 LAST $XR0 157 
J 0
(-411 2925);
DISPLAY 0.638298 (-411 2925);
PAINT MONO (-411 2925);
FORCEPROP 2 LAST CDS_LIB mstr_standard
J 0
(-600 2925);
PAINT MONO (-600 2925);
DISPLAY INVISIBLE (-600 2925);
FORCEPROP 1 LAST COMMENT_BODY TRUE
J 0
(-645 2830);
DISPLAY 0.872340 (-645 2830);
PAINT GREEN (-645 2830);
DISPLAY INVISIBLE (-645 2830);
FORCEPROP 2 LAST PATH I359
J 0
(-550 3000);
DISPLAY 1.021277 (-550 3000);
PAINT ORANGE (-550 3000);
DISPLAY INVISIBLE (-550 3000);
FORCEPROP 1 LAST OFFPAGE TRUE
J 0
(-275 2800);
DISPLAY 0.872340 (-275 2800);
PAINT GREEN (-275 2800);
DISPLAY INVISIBLE (-275 2800);
FORCEADD OFFPAGE..2
(-5950 2200);
FORCEPROP 2 LAST $XR2 145 
J 0
(-5521 2200);
DISPLAY 0.638298 (-5521 2200);
PAINT MONO (-5521 2200);
FORCEPROP 2 LAST $XR1 136 
J 0
(-5641 2200);
DISPLAY 0.638298 (-5641 2200);
PAINT MONO (-5641 2200);
FORCEPROP 2 LAST $XR0 120 
J 0
(-5761 2200);
DISPLAY 0.638298 (-5761 2200);
PAINT MONO (-5761 2200);
FORCEPROP 2 LAST PATH I360
J 0
(-5500 2250);
DISPLAY 1.021277 (-5500 2250);
PAINT ORANGE (-5500 2250);
DISPLAY INVISIBLE (-5500 2250);
FORCEPROP 1 LAST OFFPAGE TRUE
J 0
(-5625 2075);
DISPLAY 0.872340 (-5625 2075);
PAINT GREEN (-5625 2075);
DISPLAY INVISIBLE (-5625 2075);
FORCEPROP 2 LAST CDS_LIB mstr_standard
J 0
(-5950 2200);
PAINT MONO (-5950 2200);
DISPLAY INVISIBLE (-5950 2200);
FORCEPROP 1 LAST COMMENT_BODY TRUE
J 0
(-5995 2105);
DISPLAY 0.872340 (-5995 2105);
PAINT GREEN (-5995 2105);
DISPLAY INVISIBLE (-5995 2105);
FORCEADD RES..1
(-7175 2200);
FORCEPROP 1 LAST LOCATION R8E19
J 0
(-7225 2250);
DISPLAY 0.617021 (-7225 2250);
PAINT AQUA (-7225 2250);
FORCEPROP 1 LAST WATTAGE 1/16W
J 2
(-6750 2150);
DISPLAY 0.617021 (-6750 2150);
PAINT SKYBLUE (-6750 2150);
FORCEPROP 1 LAST MATERIAL EMPTY
J 0
(-6925 2100);
DISPLAY 0.617021 (-6925 2100);
PAINT RED (-6925 2100);
FORCEPROP 1 LAST PACK_TYPE 0402
J 0
(-7000 2150);
DISPLAY 0.617021 (-7000 2150);
PAINT SKYBLUE (-7000 2150);
FORCEPROP 1 LASTPIN (-7075 2200) $PN 2
J 0
(-7113 2212);
DISPLAY 0.617021 (-7113 2212);
PAINT ORANGE (-7113 2212);
FORCEPROP 1 LAST TOLERANCE 1%
J 0
(-7125 2150);
DISPLAY 0.617021 (-7125 2150);
PAINT SKYBLUE (-7125 2150);
FORCEPROP 1 LAST PART_NUMBER G21796-072
J 0
(-7400 2100);
DISPLAY 0.617021 (-7400 2100);
PAINT BLUE (-7400 2100);
FORCEPROP 1 LASTPIN (-7275 2200) $PN 1
J 0
(-7263 2212);
DISPLAY 0.617021 (-7263 2212);
PAINT ORANGE (-7263 2212);
FORCEPROP 1 LAST VALUE 4.75K
J 2
(-7200 2150);
DISPLAY 0.617021 (-7200 2150);
PAINT SKYBLUE (-7200 2150);
FORCEPROP 2 LAST BOM_COST SM_CONTROLLER
J 0
(-7225 2350);
DISPLAY 1.021277 (-7225 2350);
PAINT ORANGE (-7225 2350);
DISPLAY INVISIBLE (-7225 2350);
FORCEPROP 2 LAST SEC_TYPE 0402
J 0
(-7225 2400);
DISPLAY 1.021277 (-7225 2400);
PAINT ORANGE (-7225 2400);
DISPLAY INVISIBLE (-7225 2400);
FORCEPROP 2 LAST SEC 1
J 0
(-7225 2400);
PAINT MONO (-7225 2400);
DISPLAY INVISIBLE (-7225 2400);
FORCEPROP 1 LAST PATH I361
J 0
(-7225 2350);
DISPLAY 0.978723 (-7225 2350);
PAINT WHITE (-7225 2350);
DISPLAY INVISIBLE (-7225 2350);
FORCEPROP 2 LAST ROOM BMC_MISC
J 0
(-7225 2300);
DISPLAY 1.021277 (-7225 2300);
PAINT ORANGE (-7225 2300);
DISPLAY INVISIBLE (-7225 2300);
FORCEPROP 2 LAST CDS_LOCATION R8E19
J 0
(-7225 2250);
DISPLAY 0.617021 (-7225 2250);
PAINT AQUA (-7225 2250);
DISPLAY INVISIBLE (-7225 2250);
FORCEPROP 2 LAST CDS_LIB mstr_discrete
J 0
(-7175 2200);
PAINT ORANGE (-7175 2200);
DISPLAY INVISIBLE (-7175 2200);
FORCEADD P3V3_STBY..1
(-5250 4675);
FORCEPROP 3 LASTPIN (-5250 4625) SIG_NAME P3V3_STBY\g
J 0
(-5240 4635);
DISPLAY 0.659574 (-5240 4635);
PAINT MONO (-5240 4635);
DISPLAY INVISIBLE (-5240 4635);
FORCEPROP 1 LAST VOLTAGE 3.3V
J 0
(-5295 4632);
DISPLAY 0.340426 (-5295 4632);
PAINT SKYBLUE (-5295 4632);
DISPLAY INVISIBLE (-5295 4632);
FORCEPROP 2 LAST CDS_LIB mstr_symbols
J 0
(-5250 4675);
PAINT ORANGE (-5250 4675);
DISPLAY INVISIBLE (-5250 4675);
FORCEPROP 1 LAST SIZE 1B
J 0
(-5205 4697);
DISPLAY 0.340426 (-5205 4697);
PAINT GREEN (-5205 4697);
DISPLAY INVISIBLE (-5205 4697);
FORCEPROP 1 LAST BODY_TYPE PLUMBING
J 0
(-5295 4632);
DISPLAY 0.340426 (-5295 4632);
PAINT GREEN (-5295 4632);
DISPLAY INVISIBLE (-5295 4632);
FORCEPROP 1 LAST PATH I362
J 0
(-5205 4677);
DISPLAY 0.340426 (-5205 4677);
PAINT GREEN (-5205 4677);
DISPLAY INVISIBLE (-5205 4677);
FORCEPROP 1 LAST HDL_POWER P3V3_STBY
J 0
(-5550 4550);
DISPLAY 0.872340 (-5550 4550);
PAINT ORANGE (-5550 4550);
DISPLAY INVISIBLE (-5550 4550);
FORCEADD OFFPAGE..2
(-3700 4025);
FORCEPROP 2 LAST $XR2 190 
J 0
(-3271 4025);
DISPLAY 0.638298 (-3271 4025);
PAINT MONO (-3271 4025);
FORCEPROP 2 LAST $XR1 145 
J 0
(-3391 4025);
DISPLAY 0.638298 (-3391 4025);
PAINT MONO (-3391 4025);
FORCEPROP 2 LAST $XR0 119 
J 0
(-3511 4025);
DISPLAY 0.638298 (-3511 4025);
PAINT MONO (-3511 4025);
FORCEPROP 2 LAST PATH I366
J 0
(-3250 4075);
DISPLAY 1.021277 (-3250 4075);
PAINT ORANGE (-3250 4075);
DISPLAY INVISIBLE (-3250 4075);
FORCEPROP 1 LAST OFFPAGE TRUE
J 0
(-3375 3900);
DISPLAY 0.872340 (-3375 3900);
PAINT GREEN (-3375 3900);
DISPLAY INVISIBLE (-3375 3900);
FORCEPROP 1 LAST COMMENT_BODY TRUE
J 0
(-3745 3930);
DISPLAY 0.872340 (-3745 3930);
PAINT GREEN (-3745 3930);
DISPLAY INVISIBLE (-3745 3930);
FORCEPROP 2 LAST CDS_LIB mstr_standard
J 0
(-3700 4025);
PAINT MONO (-3700 4025);
DISPLAY INVISIBLE (-3700 4025);
FORCEADD RES..1
(-4925 4025);
FORCEPROP 1 LAST LOCATION R2U4
J 0
(-4975 4075);
DISPLAY 0.617021 (-4975 4075);
PAINT AQUA (-4975 4075);
FORCEPROP 1 LAST VALUE 4.75K
J 2
(-4950 3975);
DISPLAY 0.617021 (-4950 3975);
PAINT SKYBLUE (-4950 3975);
FORCEPROP 1 LAST MATERIAL CHIP
J 0
(-4675 3925);
DISPLAY 0.617021 (-4675 3925);
PAINT SKYBLUE (-4675 3925);
FORCEPROP 1 LAST PACK_TYPE 0402
J 0
(-4750 3975);
DISPLAY 0.617021 (-4750 3975);
PAINT SKYBLUE (-4750 3975);
FORCEPROP 1 LAST TOLERANCE 1%
J 0
(-4875 3975);
DISPLAY 0.617021 (-4875 3975);
PAINT SKYBLUE (-4875 3975);
FORCEPROP 1 LAST WATTAGE 1/16W
J 2
(-4500 3975);
DISPLAY 0.617021 (-4500 3975);
PAINT SKYBLUE (-4500 3975);
FORCEPROP 1 LASTPIN (-4825 4025) $PN 2
J 0
(-4863 4037);
DISPLAY 0.617021 (-4863 4037);
PAINT ORANGE (-4863 4037);
FORCEPROP 1 LASTPIN (-5025 4025) $PN 1
J 0
(-5013 4037);
DISPLAY 0.617021 (-5013 4037);
PAINT ORANGE (-5013 4037);
FORCEPROP 1 LAST PART_NUMBER G21796-072
J 0
(-5150 3925);
DISPLAY 0.617021 (-5150 3925);
PAINT BLUE (-5150 3925);
FORCEPROP 2 LAST SEC_TYPE 0402
J 0
(-4975 4225);
DISPLAY 1.021277 (-4975 4225);
PAINT ORANGE (-4975 4225);
DISPLAY INVISIBLE (-4975 4225);
FORCEPROP 2 LAST BOM_COST SM_CONTROLLER
J 0
(-4975 4175);
DISPLAY 1.021277 (-4975 4175);
PAINT ORANGE (-4975 4175);
DISPLAY INVISIBLE (-4975 4175);
FORCEPROP 2 LAST SEC 1
J 0
(-4975 4225);
PAINT MONO (-4975 4225);
DISPLAY INVISIBLE (-4975 4225);
FORCEPROP 1 LAST PATH I367
J 0
(-4975 4175);
DISPLAY 0.978723 (-4975 4175);
PAINT WHITE (-4975 4175);
DISPLAY INVISIBLE (-4975 4175);
FORCEPROP 2 LAST ROOM BMC_MISC
J 0
(-4975 4125);
DISPLAY 1.021277 (-4975 4125);
PAINT ORANGE (-4975 4125);
DISPLAY INVISIBLE (-4975 4125);
FORCEPROP 2 LAST CDS_LOCATION R2U4
J 0
(-4975 4075);
DISPLAY 0.617021 (-4975 4075);
PAINT AQUA (-4975 4075);
DISPLAY INVISIBLE (-4975 4075);
FORCEPROP 2 LAST CDS_LIB mstr_discrete
J 0
(-4925 4025);
PAINT ORANGE (-4925 4025);
DISPLAY INVISIBLE (-4925 4025);
FORCEADD RES..1
(-6975 775);
FORCEPROP 1 LASTPIN (-6875 775) $PN 2
J 0
(-6913 787);
DISPLAY 0.617021 (-6913 787);
PAINT ORANGE (-6913 787);
FORCEPROP 1 LAST TOLERANCE 1%
J 0
(-6975 675);
DISPLAY 0.617021 (-6975 675);
PAINT SKYBLUE (-6975 675);
FORCEPROP 1 LAST MATERIAL CHIP
J 0
(-6975 625);
DISPLAY 0.617021 (-6975 625);
PAINT SKYBLUE (-6975 625);
FORCEPROP 1 LAST PART_NUMBER G21796-026
J 0
(-7100 575);
DISPLAY 0.617021 (-7100 575);
PAINT BLUE (-7100 575);
FORCEPROP 1 LAST WATTAGE 1/16W
J 2
(-7000 625);
DISPLAY 0.617021 (-7000 625);
PAINT SKYBLUE (-7000 625);
FORCEPROP 1 LAST VALUE 1.00K
J 2
(-7000 675);
DISPLAY 0.617021 (-7000 675);
PAINT SKYBLUE (-7000 675);
FORCEPROP 1 LAST LOCATION R4R1
J 0
(-7025 825);
DISPLAY 0.617021 (-7025 825);
PAINT AQUA (-7025 825);
FORCEPROP 1 LASTPIN (-7075 775) $PN 1
J 0
(-7063 787);
DISPLAY 0.617021 (-7063 787);
PAINT ORANGE (-7063 787);
FORCEPROP 1 LAST PACK_TYPE 0402
J 0
(-6850 625);
DISPLAY 0.617021 (-6850 625);
PAINT SKYBLUE (-6850 625);
FORCEPROP 2 LAST CDS_LIB mstr_discrete
J 0
(-6975 775);
PAINT ORANGE (-6975 775);
DISPLAY INVISIBLE (-6975 775);
FORCEPROP 2 LAST SEC_TYPE 0402
J 0
(-7025 975);
DISPLAY 1.021277 (-7025 975);
PAINT ORANGE (-7025 975);
DISPLAY INVISIBLE (-7025 975);
FORCEPROP 2 LAST SEC 1
J 0
(-7025 975);
DISPLAY 0.680851 (-7025 975);
PAINT MONO (-7025 975);
DISPLAY INVISIBLE (-7025 975);
FORCEPROP 2 LAST CDS_LOCATION R4R1
J 0
(-7025 825);
DISPLAY 0.617021 (-7025 825);
PAINT AQUA (-7025 825);
DISPLAY INVISIBLE (-7025 825);
FORCEPROP 1 LAST PATH I368
J 0
(-7025 925);
DISPLAY 0.978723 (-7025 925);
PAINT WHITE (-7025 925);
DISPLAY INVISIBLE (-7025 925);
FORCEPROP 0 LAST ROOM MIO_CHASSIS
J 0
(-7025 975);
DISPLAY 1.021277 (-7025 975);
PAINT ORANGE (-7025 975);
DISPLAY INVISIBLE (-7025 975);
FORCEPROP 0 LAST BOM_COST MIO_CHASSIS
J 0
(-7025 1075);
DISPLAY 1.021277 (-7025 1075);
PAINT ORANGE (-7025 1075);
DISPLAY INVISIBLE (-7025 1075);
FORCEADD P3V3_STBY..1
(-1700 2825);
FORCEPROP 3 LASTPIN (-1700 2775) SIG_NAME P3V3_STBY\g
J 0
(-1690 2785);
DISPLAY 0.659574 (-1690 2785);
PAINT MONO (-1690 2785);
DISPLAY INVISIBLE (-1690 2785);
FORCEPROP 1 LAST HDL_POWER P3V3_STBY
J 0
(-2000 2700);
DISPLAY 0.872340 (-2000 2700);
PAINT ORANGE (-2000 2700);
DISPLAY INVISIBLE (-2000 2700);
FORCEPROP 1 LAST VOLTAGE 3.3V
J 0
(-1745 2782);
DISPLAY 0.340426 (-1745 2782);
PAINT SKYBLUE (-1745 2782);
DISPLAY INVISIBLE (-1745 2782);
FORCEPROP 2 LAST CDS_LIB mstr_symbols
J 0
(-1700 2825);
PAINT ORANGE (-1700 2825);
DISPLAY INVISIBLE (-1700 2825);
FORCEPROP 1 LAST BODY_TYPE PLUMBING
J 0
(-1745 2782);
DISPLAY 0.340426 (-1745 2782);
PAINT GREEN (-1745 2782);
DISPLAY INVISIBLE (-1745 2782);
FORCEPROP 1 LAST SIZE 1B
J 0
(-1655 2847);
DISPLAY 0.340426 (-1655 2847);
PAINT GREEN (-1655 2847);
DISPLAY INVISIBLE (-1655 2847);
FORCEPROP 1 LAST PATH I369
J 0
(-1655 2827);
DISPLAY 0.340426 (-1655 2827);
PAINT GREEN (-1655 2827);
DISPLAY INVISIBLE (-1655 2827);
FORCEADD CAP_A..1
(-1700 2575);
FORCEPROP 1 LAST PART_NUMBER A36096-030
J 0
(-1650 2425);
DISPLAY 0.617021 (-1650 2425);
PAINT BLUE (-1650 2425);
FORCEPROP 1 LAST MATERIAL X7R
J 0
(-1650 2475);
DISPLAY 0.617021 (-1650 2475);
PAINT SKYBLUE (-1650 2475);
FORCEPROP 1 LAST VOLTAGE 16V
J 0
(-1650 2575);
DISPLAY 0.617021 (-1650 2575);
PAINT SKYBLUE (-1650 2575);
FORCEPROP 1 LAST PACK_TYPE 0402V
J 0
(-1650 2375);
DISPLAY 0.617021 (-1650 2375);
PAINT SKYBLUE (-1650 2375);
FORCEPROP 1 LAST TOLERANCE 10%
J 0
(-1650 2525);
DISPLAY 0.617021 (-1650 2525);
PAINT SKYBLUE (-1650 2525);
FORCEPROP 1 LAST VALUE 0.1UF
J 0
(-1650 2625);
DISPLAY 0.617021 (-1650 2625);
PAINT SKYBLUE (-1650 2625);
FORCEPROP 1 LAST LOCATION C2T3
J 0
(-1650 2675);
DISPLAY 0.617021 (-1650 2675);
PAINT AQUA (-1650 2675);
FORCEPROP 1 LASTPIN (-1700 2675) $PN 1
J 0
(-1690 2655);
DISPLAY 0.617021 (-1690 2655);
PAINT ORANGE (-1690 2655);
FORCEPROP 1 LASTPIN (-1700 2475) $PN 2
J 0
(-1690 2455);
DISPLAY 0.617021 (-1690 2455);
PAINT ORANGE (-1690 2455);
FORCEPROP 2 LAST SEC 1
J 0
(-1650 2725);
DISPLAY 0.680851 (-1650 2725);
PAINT MONO (-1650 2725);
DISPLAY INVISIBLE (-1650 2725);
FORCEPROP 2 LAST SEC_TYPE 0402V
J 0
(-1650 2775);
DISPLAY 1.021277 (-1650 2775);
PAINT ORANGE (-1650 2775);
DISPLAY INVISIBLE (-1650 2775);
FORCEPROP 2 LAST CDS_SEC 1
J 0
(-1650 2725);
PAINT ORANGE (-1650 2725);
DISPLAY INVISIBLE (-1650 2725);
FORCEPROP 2 LAST BOM_COST MIO_CHASSIS
J 0
(-1650 2775);
DISPLAY 1.021277 (-1650 2775);
PAINT ORANGE (-1650 2775);
DISPLAY INVISIBLE (-1650 2775);
FORCEPROP 2 LAST ROOM MIO_CHASSIS
J 0
(-1650 2725);
DISPLAY 1.021277 (-1650 2725);
PAINT ORANGE (-1650 2725);
DISPLAY INVISIBLE (-1650 2725);
FORCEPROP 1 LAST PATH I370
J 0
(-1650 2725);
DISPLAY 0.978723 (-1650 2725);
PAINT WHITE (-1650 2725);
DISPLAY INVISIBLE (-1650 2725);
FORCEPROP 2 LAST CDS_LOCATION C2T3
J 0
(-1650 2675);
DISPLAY 0.617021 (-1650 2675);
PAINT AQUA (-1650 2675);
DISPLAY INVISIBLE (-1650 2675);
FORCEPROP 2 LAST CDS_LIB dev_discrete
J 0
(-1700 2575);
PAINT ORANGE (-1700 2575);
DISPLAY INVISIBLE (-1700 2575);
FORCEADD GND..1
(-1700 2375);
FORCEPROP 3 LASTPIN (-1700 2425) SIG_NAME GND\g
J 0
(-1690 2435);
DISPLAY 0.659574 (-1690 2435);
PAINT MONO (-1690 2435);
DISPLAY INVISIBLE (-1690 2435);
FORCEPROP 2 LAST CDS_LIB mstr_symbols
J 0
(-1700 2375);
PAINT ORANGE (-1700 2375);
DISPLAY INVISIBLE (-1700 2375);
FORCEPROP 1 LAST VOLTAGE 0.0V
J 0
(-1745 2332);
DISPLAY 0.340426 (-1745 2332);
PAINT SKYBLUE (-1745 2332);
DISPLAY INVISIBLE (-1745 2332);
FORCEPROP 1 LAST HDL_POWER GND
J 0
(-1700 2525);
DISPLAY 0.872340 (-1700 2525);
PAINT GREEN (-1700 2525);
DISPLAY INVISIBLE (-1700 2525);
FORCEPROP 1 LAST BODY_TYPE PLUMBING
J 0
(-1745 2332);
DISPLAY 0.340426 (-1745 2332);
PAINT GREEN (-1745 2332);
DISPLAY INVISIBLE (-1745 2332);
FORCEPROP 1 LAST SIZE 1B
J 0
(-1625 2325);
DISPLAY 0.872340 (-1625 2325);
PAINT AQUA (-1625 2325);
DISPLAY INVISIBLE (-1625 2325);
FORCEPROP 1 LAST PATH I371
J 0
(-1625 2375);
DISPLAY 0.872340 (-1625 2375);
PAINT AQUA (-1625 2375);
DISPLAY INVISIBLE (-1625 2375);
FORCEADD OFFPAGE..1
(-3500 1150);
FORCEPROP 2 LAST $XR4 247 
J 0
(-4232 1150);
DISPLAY 0.638298 (-4232 1150);
PAINT MONO (-4232 1150);
FORCEPROP 2 LAST $XR3 191 
J 0
(-4112 1150);
DISPLAY 0.638298 (-4112 1150);
PAINT MONO (-4112 1150);
FORCEPROP 2 LAST $XR2 118 
J 0
(-3992 1150);
DISPLAY 0.638298 (-3992 1150);
PAINT MONO (-3992 1150);
FORCEPROP 2 LAST $XR1 200 
J 0
(-3872 1150);
DISPLAY 0.638298 (-3872 1150);
PAINT MONO (-3872 1150);
FORCEPROP 2 LAST $XR0 196 
J 0
(-3752 1150);
DISPLAY 0.638298 (-3752 1150);
PAINT MONO (-3752 1150);
FORCEPROP 2 LAST PATH I373
J 0
(-3450 1225);
DISPLAY 1.021277 (-3450 1225);
PAINT ORANGE (-3450 1225);
DISPLAY INVISIBLE (-3450 1225);
FORCEPROP 1 LAST COMMENT_BODY TRUE
J 0
(-3375 1050);
DISPLAY 0.872340 (-3375 1050);
PAINT GREEN (-3375 1050);
DISPLAY INVISIBLE (-3375 1050);
FORCEPROP 1 LAST OFFPAGE TRUE
J 0
(-3175 1025);
DISPLAY 0.872340 (-3175 1025);
PAINT GREEN (-3175 1025);
DISPLAY INVISIBLE (-3175 1025);
FORCEPROP 2 LAST CDS_LIB mstr_standard
J 0
(-3500 1150);
PAINT ORANGE (-3500 1150);
DISPLAY INVISIBLE (-3500 1150);
FORCEADD TTL1G07_A..1
(-2800 1150);
FORCEPROP 2 LASTPIN (-2650 1150) SIG_NAME RST_BMC_SRST_R2_N
J 0
(-2560 1160);
DISPLAY 0.617021 (-2560 1160);
PAINT ORANGE (-2560 1160);
FORCEPROP 2 LASTPROP $XRERR UNIQUE?
J 0
(-2800 1160);
DISPLAY 0.638298 (-2800 1160);
PAINT MONO (-2800 1160);
DISPLAY INVISIBLE (-2800 1160);
FORCEPROP 1 LAST POWER_GROUP VCC=P3V3_STBY;GND=GND
J 1
(-2850 960);
DISPLAY 0.617021 (-2850 960);
PAINT ORANGE (-2850 960);
FORCEPROP 1 LAST PART_NUMBER C88419-001
J 0
(-2850 1015);
DISPLAY 0.617021 (-2850 1015);
PAINT BLUE (-2850 1015);
FORCEPROP 2 LASTPIN (-2650 1150) $PN 4
J 0
(-2640 1160);
DISPLAY 0.617021 (-2640 1160);
PAINT ORANGE (-2640 1160);
FORCEPROP 1 LAST LOCATION U8D2
J 0
(-2850 1350);
DISPLAY 0.617021 (-2850 1350);
PAINT AQUA (-2850 1350);
FORCEPROP 1 LAST MATERIAL IC
J 0
(-2850 1300);
DISPLAY 0.617021 (-2850 1300);
PAINT SKYBLUE (-2850 1300);
FORCEPROP 1 LAST VALUE 74LVC1G07
J 1
(-2800 1250);
DISPLAY 0.617021 (-2800 1250);
PAINT SKYBLUE (-2800 1250);
FORCEPROP 2 LASTPIN (-2900 1150) $PN 2
J 2
(-2910 1160);
DISPLAY 0.617021 (-2910 1160);
PAINT ORANGE (-2910 1160);
FORCEPROP 2 LAST CDS_LOCATION U8D2
J 0
(-2850 1350);
DISPLAY 0.617021 (-2850 1350);
PAINT AQUA (-2850 1350);
DISPLAY INVISIBLE (-2850 1350);
FORCEPROP 2 LAST SEC 1
J 0
(-2850 1400);
DISPLAY 0.680851 (-2850 1400);
PAINT MONO (-2850 1400);
DISPLAY INVISIBLE (-2850 1400);
FORCEPROP 2 LAST SEC_TYPE SOP
J 0
(-2850 1400);
DISPLAY 1.021277 (-2850 1400);
PAINT ORANGE (-2850 1400);
DISPLAY INVISIBLE (-2850 1400);
FORCEPROP 1 LAST PACK_TYPE SOP
J 0
(-2850 1400);
DISPLAY 0.978723 (-2850 1400);
PAINT SKYBLUE (-2850 1400);
DISPLAY INVISIBLE (-2850 1400);
FORCEPROP 1 LAST PATH I374
J 0
(-2750 1200);
DISPLAY 0.978723 (-2750 1200);
PAINT WHITE (-2750 1200);
DISPLAY INVISIBLE (-2750 1200);
FORCEPROP 2 LAST CDS_LIB mstr_ttl
J 0
(-2800 1150);
PAINT ORANGE (-2800 1150);
DISPLAY INVISIBLE (-2800 1150);
FORCEADD OFFPAGE..2
(-800 1150);
FORCEPROP 2 LAST $XR2 249 
J 0
(-371 1150);
DISPLAY 0.638298 (-371 1150);
PAINT MONO (-371 1150);
FORCEPROP 2 LAST $XR1 184 
J 0
(-491 1150);
DISPLAY 0.638298 (-491 1150);
PAINT MONO (-491 1150);
FORCEPROP 2 LAST $XR0 119 
J 0
(-611 1150);
DISPLAY 0.638298 (-611 1150);
PAINT MONO (-611 1150);
FORCEPROP 1 LAST OFFPAGE TRUE
J 0
(-475 1025);
DISPLAY 0.872340 (-475 1025);
PAINT GREEN (-475 1025);
DISPLAY INVISIBLE (-475 1025);
FORCEPROP 2 LAST PATH I375
J 0
(-750 1225);
DISPLAY 1.021277 (-750 1225);
PAINT ORANGE (-750 1225);
DISPLAY INVISIBLE (-750 1225);
FORCEPROP 1 LAST COMMENT_BODY TRUE
J 0
(-845 1055);
DISPLAY 0.872340 (-845 1055);
PAINT GREEN (-845 1055);
DISPLAY INVISIBLE (-845 1055);
FORCEPROP 2 LAST CDS_LIB mstr_standard
J 0
(-800 1150);
PAINT ORANGE (-800 1150);
DISPLAY INVISIBLE (-800 1150);
FORCEADD CAP_A..1
(-500 1750);
FORCEPROP 1 LASTPIN (-500 1650) $PN 2
J 0
(-490 1630);
DISPLAY 0.617021 (-490 1630);
PAINT ORANGE (-490 1630);
FORCEPROP 1 LASTPIN (-500 1850) $PN 1
J 0
(-490 1830);
DISPLAY 0.617021 (-490 1830);
PAINT ORANGE (-490 1830);
FORCEPROP 1 LAST LOCATION C8D1
J 0
(-450 1850);
DISPLAY 0.617021 (-450 1850);
PAINT AQUA (-450 1850);
FORCEPROP 1 LAST VALUE 0.1UF
J 0
(-450 1800);
DISPLAY 0.617021 (-450 1800);
PAINT SKYBLUE (-450 1800);
FORCEPROP 1 LAST VOLTAGE 16V
J 0
(-450 1750);
DISPLAY 0.617021 (-450 1750);
PAINT SKYBLUE (-450 1750);
FORCEPROP 1 LAST TOLERANCE 10%
J 0
(-450 1700);
DISPLAY 0.617021 (-450 1700);
PAINT SKYBLUE (-450 1700);
FORCEPROP 1 LAST MATERIAL X7R
J 0
(-450 1650);
DISPLAY 0.617021 (-450 1650);
PAINT SKYBLUE (-450 1650);
FORCEPROP 1 LAST PART_NUMBER A36096-030
J 0
(-450 1600);
DISPLAY 0.617021 (-450 1600);
PAINT BLUE (-450 1600);
FORCEPROP 1 LAST PACK_TYPE 0402V
J 0
(-450 1550);
DISPLAY 0.617021 (-450 1550);
PAINT SKYBLUE (-450 1550);
FORCEPROP 2 LAST CDS_LIB dev_discrete
J 0
(-500 1750);
PAINT ORANGE (-500 1750);
DISPLAY INVISIBLE (-500 1750);
FORCEPROP 2 LAST CDS_SEC 1
J 0
(-450 1900);
PAINT ORANGE (-450 1900);
DISPLAY INVISIBLE (-450 1900);
FORCEPROP 2 LAST CDS_LOCATION C8D1
J 0
(-450 1850);
DISPLAY 0.617021 (-450 1850);
PAINT AQUA (-450 1850);
DISPLAY INVISIBLE (-450 1850);
FORCEPROP 1 LAST PATH I376
J 0
(-450 1900);
DISPLAY 0.978723 (-450 1900);
PAINT WHITE (-450 1900);
DISPLAY INVISIBLE (-450 1900);
FORCEPROP 2 LAST SEC 1
J 0
(-450 1950);
DISPLAY 0.680851 (-450 1950);
PAINT MONO (-450 1950);
DISPLAY INVISIBLE (-450 1950);
FORCEPROP 2 LAST SEC_TYPE 0402V
J 0
(-450 1950);
DISPLAY 1.021277 (-450 1950);
PAINT ORANGE (-450 1950);
DISPLAY INVISIBLE (-450 1950);
FORCEADD GND..1
(-500 1575);
FORCEPROP 3 LASTPIN (-500 1625) SIG_NAME GND\g
J 0
(-490 1635);
DISPLAY 0.659574 (-490 1635);
PAINT MONO (-490 1635);
DISPLAY INVISIBLE (-490 1635);
FORCEPROP 1 LAST BODY_TYPE PLUMBING
J 0
(-545 1532);
DISPLAY 0.340426 (-545 1532);
PAINT GREEN (-545 1532);
DISPLAY INVISIBLE (-545 1532);
FORCEPROP 1 LAST VOLTAGE 0.0V
J 0
(-545 1532);
DISPLAY 0.340426 (-545 1532);
PAINT SKYBLUE (-545 1532);
DISPLAY INVISIBLE (-545 1532);
FORCEPROP 1 LAST PATH I377
J 0
(-425 1575);
DISPLAY 0.872340 (-425 1575);
PAINT AQUA (-425 1575);
DISPLAY INVISIBLE (-425 1575);
FORCEPROP 1 LAST SIZE 1B
J 0
(-425 1525);
DISPLAY 0.872340 (-425 1525);
PAINT AQUA (-425 1525);
DISPLAY INVISIBLE (-425 1525);
FORCEPROP 2 LAST CDS_LIB mstr_symbols
J 0
(-500 1575);
PAINT ORANGE (-500 1575);
DISPLAY INVISIBLE (-500 1575);
FORCEPROP 1 LAST HDL_POWER GND
J 0
(-500 1725);
DISPLAY 0.872340 (-500 1725);
PAINT GREEN (-500 1725);
DISPLAY INVISIBLE (-500 1725);
FORCEADD P3V3_STBY..1
(-500 1950);
FORCEPROP 3 LASTPIN (-500 1900) SIG_NAME P3V3_STBY\g
J 0
(-490 1910);
DISPLAY 0.659574 (-490 1910);
PAINT MONO (-490 1910);
DISPLAY INVISIBLE (-490 1910);
FORCEPROP 2 LAST CDS_LIB mstr_symbols
J 0
(-500 1950);
PAINT ORANGE (-500 1950);
DISPLAY INVISIBLE (-500 1950);
FORCEPROP 1 LAST SIZE 1B
J 0
(-455 1972);
DISPLAY 0.340426 (-455 1972);
PAINT GREEN (-455 1972);
DISPLAY INVISIBLE (-455 1972);
FORCEPROP 1 LAST PATH I378
J 0
(-455 1952);
DISPLAY 0.340426 (-455 1952);
PAINT GREEN (-455 1952);
DISPLAY INVISIBLE (-455 1952);
FORCEPROP 1 LAST VOLTAGE 3.3V
J 0
(-545 1907);
DISPLAY 0.340426 (-545 1907);
PAINT SKYBLUE (-545 1907);
DISPLAY INVISIBLE (-545 1907);
FORCEPROP 1 LAST BODY_TYPE PLUMBING
J 0
(-545 1907);
DISPLAY 0.340426 (-545 1907);
PAINT GREEN (-545 1907);
DISPLAY INVISIBLE (-545 1907);
FORCEPROP 1 LAST HDL_POWER P3V3_STBY
J 0
(-800 1825);
DISPLAY 0.872340 (-800 1825);
PAINT ORANGE (-800 1825);
DISPLAY INVISIBLE (-800 1825);
FORCEADD OFFPAGE..2
(-800 875);
FORCEPROP 2 LAST $XR0 119 
J 0
(-611 875);
DISPLAY 0.638298 (-611 875);
PAINT MONO (-611 875);
FORCEPROP 2 LAST CDS_LIB mstr_standard
J 0
(-800 875);
PAINT ORANGE (-800 875);
DISPLAY INVISIBLE (-800 875);
FORCEPROP 2 LAST PATH I380
J 0
(-750 950);
DISPLAY 1.021277 (-750 950);
PAINT ORANGE (-750 950);
DISPLAY INVISIBLE (-750 950);
FORCEPROP 1 LAST OFFPAGE TRUE
J 0
(-475 750);
DISPLAY 0.872340 (-475 750);
PAINT GREEN (-475 750);
DISPLAY INVISIBLE (-475 750);
FORCEPROP 1 LAST COMMENT_BODY TRUE
J 0
(-845 780);
DISPLAY 0.872340 (-845 780);
PAINT GREEN (-845 780);
DISPLAY INVISIBLE (-845 780);
FORCEADD OFFPAGE..2
(-5950 3425);
FORCEPROP 2 LAST $XR2 190 
J 0
(-5521 3425);
DISPLAY 0.638298 (-5521 3425);
PAINT MONO (-5521 3425);
FORCEPROP 2 LAST $XR1 147 
J 0
(-5641 3425);
DISPLAY 0.638298 (-5641 3425);
PAINT MONO (-5641 3425);
FORCEPROP 2 LAST $XR0 118 
J 0
(-5761 3425);
DISPLAY 0.638298 (-5761 3425);
PAINT MONO (-5761 3425);
FORCEPROP 2 LAST PATH I381
J 0
(-5500 3475);
DISPLAY 1.021277 (-5500 3475);
PAINT ORANGE (-5500 3475);
DISPLAY INVISIBLE (-5500 3475);
FORCEPROP 1 LAST OFFPAGE TRUE
J 0
(-5625 3300);
DISPLAY 0.872340 (-5625 3300);
PAINT GREEN (-5625 3300);
DISPLAY INVISIBLE (-5625 3300);
FORCEPROP 2 LAST CDS_LIB mstr_standard
J 0
(-5950 3425);
PAINT ORANGE (-5950 3425);
DISPLAY INVISIBLE (-5950 3425);
FORCEPROP 1 LAST COMMENT_BODY TRUE
J 0
(-5995 3330);
DISPLAY 0.872340 (-5995 3330);
PAINT GREEN (-5995 3330);
DISPLAY INVISIBLE (-5995 3330);
FORCEADD RES..1
(-7175 3425);
FORCEPROP 1 LAST TOLERANCE 1%
J 0
(-7125 3375);
DISPLAY 0.617021 (-7125 3375);
PAINT SKYBLUE (-7125 3375);
FORCEPROP 1 LAST PART_NUMBER G21796-072
J 0
(-7400 3325);
DISPLAY 0.617021 (-7400 3325);
PAINT BLUE (-7400 3325);
FORCEPROP 1 LAST VALUE 4.75K
J 2
(-7200 3375);
DISPLAY 0.617021 (-7200 3375);
PAINT SKYBLUE (-7200 3375);
FORCEPROP 1 LAST PACK_TYPE 0402
J 0
(-7000 3375);
DISPLAY 0.617021 (-7000 3375);
PAINT SKYBLUE (-7000 3375);
FORCEPROP 1 LAST MATERIAL CHIP
J 0
(-6925 3325);
DISPLAY 0.617021 (-6925 3325);
PAINT SKYBLUE (-6925 3325);
FORCEPROP 1 LAST WATTAGE 1/16W
J 2
(-6750 3375);
DISPLAY 0.617021 (-6750 3375);
PAINT SKYBLUE (-6750 3375);
FORCEPROP 1 LASTPIN (-7075 3425) $PN 2
J 0
(-7113 3437);
DISPLAY 0.617021 (-7113 3437);
PAINT ORANGE (-7113 3437);
FORCEPROP 1 LAST LOCATION R1L7
J 0
(-7225 3475);
DISPLAY 0.617021 (-7225 3475);
PAINT AQUA (-7225 3475);
FORCEPROP 1 LASTPIN (-7275 3425) $PN 1
J 0
(-7263 3437);
DISPLAY 0.617021 (-7263 3437);
PAINT ORANGE (-7263 3437);
FORCEPROP 2 LAST SEC_TYPE 0402
J 0
(-7225 3625);
DISPLAY 1.021277 (-7225 3625);
PAINT ORANGE (-7225 3625);
DISPLAY INVISIBLE (-7225 3625);
FORCEPROP 2 LAST SEC 1
J 0
(-7225 3625);
PAINT MONO (-7225 3625);
DISPLAY INVISIBLE (-7225 3625);
FORCEPROP 2 LAST BOM_COST SM_CONTROLLER
J 0
(-7225 3575);
DISPLAY 1.021277 (-7225 3575);
PAINT ORANGE (-7225 3575);
DISPLAY INVISIBLE (-7225 3575);
FORCEPROP 1 LAST PATH I382
J 0
(-7225 3575);
DISPLAY 0.978723 (-7225 3575);
PAINT WHITE (-7225 3575);
DISPLAY INVISIBLE (-7225 3575);
FORCEPROP 2 LAST ROOM BMC_MISC
J 0
(-7225 3525);
DISPLAY 1.021277 (-7225 3525);
PAINT ORANGE (-7225 3525);
DISPLAY INVISIBLE (-7225 3525);
FORCEPROP 2 LAST CDS_LIB mstr_discrete
J 0
(-7175 3425);
PAINT ORANGE (-7175 3425);
DISPLAY INVISIBLE (-7175 3425);
FORCEPROP 2 LAST CDS_LOCATION R1L7
J 0
(-7225 3475);
DISPLAY 0.617021 (-7225 3475);
PAINT AQUA (-7225 3475);
DISPLAY INVISIBLE (-7225 3475);
FORCEADD P3V3_STBY..1
(-3975 3225);
FORCEPROP 3 LASTPIN (-3975 3175) SIG_NAME P3V3_STBY\g
J 0
(-3965 3185);
DISPLAY 0.659574 (-3965 3185);
PAINT MONO (-3965 3185);
DISPLAY INVISIBLE (-3965 3185);
FORCEPROP 1 LAST VOLTAGE 3.3V
J 0
(-4020 3182);
DISPLAY 0.340426 (-4020 3182);
PAINT SKYBLUE (-4020 3182);
DISPLAY INVISIBLE (-4020 3182);
FORCEPROP 2 LAST CDS_LIB mstr_symbols
J 0
(-3975 3225);
PAINT ORANGE (-3975 3225);
DISPLAY INVISIBLE (-3975 3225);
FORCEPROP 1 LAST SIZE 1B
J 0
(-3930 3247);
DISPLAY 0.340426 (-3930 3247);
PAINT GREEN (-3930 3247);
DISPLAY INVISIBLE (-3930 3247);
FORCEPROP 1 LAST BODY_TYPE PLUMBING
J 0
(-4020 3182);
DISPLAY 0.340426 (-4020 3182);
PAINT GREEN (-4020 3182);
DISPLAY INVISIBLE (-4020 3182);
FORCEPROP 1 LAST PATH I384
J 0
(-3930 3227);
DISPLAY 0.340426 (-3930 3227);
PAINT GREEN (-3930 3227);
DISPLAY INVISIBLE (-3930 3227);
FORCEPROP 1 LAST HDL_POWER P3V3_STBY
J 0
(-4275 3100);
DISPLAY 0.872340 (-4275 3100);
PAINT ORANGE (-4275 3100);
DISPLAY INVISIBLE (-4275 3100);
FORCEADD RES..2
(-3975 2950);
FORCEPROP 1 LAST PACK_TYPE 0402
J 0
(-3935 2775);
DISPLAY 0.617021 (-3935 2775);
PAINT SKYBLUE (-3935 2775);
FORCEPROP 1 LAST PART_NUMBER G21796-072
J 0
(-3935 2825);
DISPLAY 0.617021 (-3935 2825);
PAINT BLUE (-3935 2825);
FORCEPROP 1 LAST MATERIAL CHIP
J 0
(-3935 2875);
DISPLAY 0.617021 (-3935 2875);
PAINT SKYBLUE (-3935 2875);
FORCEPROP 1 LAST WATTAGE 1/16W
J 0
(-3935 2925);
DISPLAY 0.617021 (-3935 2925);
PAINT SKYBLUE (-3935 2925);
FORCEPROP 1 LAST TOLERANCE 1%
J 0
(-3930 2975);
DISPLAY 0.617021 (-3930 2975);
PAINT SKYBLUE (-3930 2975);
FORCEPROP 1 LAST VALUE 4.75K
J 0
(-3930 3025);
DISPLAY 0.617021 (-3930 3025);
PAINT SKYBLUE (-3930 3025);
FORCEPROP 1 LAST LOCATION R8E32
J 0
(-3930 3075);
DISPLAY 0.617021 (-3930 3075);
PAINT AQUA (-3930 3075);
FORCEPROP 1 LASTPIN (-3975 3050) $PN 1
J 0
(-3970 3012);
DISPLAY 0.617021 (-3970 3012);
PAINT ORANGE (-3970 3012);
FORCEPROP 1 LASTPIN (-3975 2850) $PN 2
J 0
(-3970 2860);
DISPLAY 0.617021 (-3970 2860);
PAINT ORANGE (-3970 2860);
FORCEPROP 0 LAST BOM_COST MIO_CHASSIS
J 0
(-3925 3275);
DISPLAY 1.021277 (-3925 3275);
PAINT ORANGE (-3925 3275);
DISPLAY INVISIBLE (-3925 3275);
FORCEPROP 2 LAST SEC_TYPE 0402
J 0
(-3925 3175);
DISPLAY 1.021277 (-3925 3175);
PAINT ORANGE (-3925 3175);
DISPLAY INVISIBLE (-3925 3175);
FORCEPROP 2 LAST SEC 1
J 0
(-3925 3175);
DISPLAY 0.680851 (-3925 3175);
PAINT MONO (-3925 3175);
DISPLAY INVISIBLE (-3925 3175);
FORCEPROP 1 LAST PATH I385
J 0
(-3925 3125);
DISPLAY 0.978723 (-3925 3125);
PAINT WHITE (-3925 3125);
DISPLAY INVISIBLE (-3925 3125);
FORCEPROP 0 LAST ROOM MIO_CHASSIS
J 0
(-3925 3175);
DISPLAY 1.021277 (-3925 3175);
PAINT ORANGE (-3925 3175);
DISPLAY INVISIBLE (-3925 3175);
FORCEPROP 2 LAST CDS_LIB mstr_discrete
J 0
(-3975 2950);
PAINT ORANGE (-3975 2950);
DISPLAY INVISIBLE (-3975 2950);
FORCEPROP 2 LAST CDS_LOCATION R8E32
J 0
(-3930 3075);
DISPLAY 0.617021 (-3930 3075);
PAINT AQUA (-3930 3075);
DISPLAY INVISIBLE (-3930 3075);
FORCEADD RES..1
(-1925 1150);
FORCEPROP 1 LAST PART_NUMBER G21796-074
J 0
(-1975 1250);
DISPLAY 0.617021 (-1975 1250);
PAINT BLUE (-1975 1250);
FORCEPROP 1 LAST LOCATION R8D22
J 0
(-1975 1200);
DISPLAY 0.617021 (-1975 1200);
PAINT AQUA (-1975 1200);
FORCEPROP 1 LAST PACK_TYPE 0402
J 0
(-1775 1000);
DISPLAY 0.617021 (-1775 1000);
PAINT SKYBLUE (-1775 1000);
FORCEPROP 1 LAST MATERIAL CHIP
J 0
(-1925 1000);
DISPLAY 0.617021 (-1925 1000);
PAINT SKYBLUE (-1925 1000);
FORCEPROP 1 LAST TOLERANCE 1%
J 0
(-1925 1050);
DISPLAY 0.617021 (-1925 1050);
PAINT SKYBLUE (-1925 1050);
FORCEPROP 1 LAST VALUE 33.2
J 2
(-1950 1050);
DISPLAY 0.617021 (-1950 1050);
PAINT SKYBLUE (-1950 1050);
FORCEPROP 1 LAST WATTAGE 1/16W
J 2
(-1950 1000);
DISPLAY 0.617021 (-1950 1000);
PAINT SKYBLUE (-1950 1000);
FORCEPROP 1 LASTPIN (-2025 1150) $PN 1
J 0
(-2013 1162);
DISPLAY 0.617021 (-2013 1162);
PAINT ORANGE (-2013 1162);
FORCEPROP 1 LASTPIN (-1825 1150) $PN 2
J 0
(-1863 1162);
DISPLAY 0.617021 (-1863 1162);
PAINT ORANGE (-1863 1162);
FORCEPROP 0 LAST ROOM BMC_MISC
J 0
(-1975 1350);
DISPLAY 1.021277 (-1975 1350);
PAINT ORANGE (-1975 1350);
DISPLAY INVISIBLE (-1975 1350);
FORCEPROP 1 LAST PATH I386
J 0
(-1975 1300);
DISPLAY 0.978723 (-1975 1300);
PAINT WHITE (-1975 1300);
DISPLAY INVISIBLE (-1975 1300);
FORCEPROP 2 LAST SEC 1
J 0
(-1975 1350);
PAINT MONO (-1975 1350);
DISPLAY INVISIBLE (-1975 1350);
FORCEPROP 0 LAST BOM_COST SM
J 0
(-1975 1450);
DISPLAY 1.021277 (-1975 1450);
PAINT ORANGE (-1975 1450);
DISPLAY INVISIBLE (-1975 1450);
FORCEPROP 2 LAST SEC_TYPE 0402
J 0
(-1975 1350);
DISPLAY 1.021277 (-1975 1350);
PAINT ORANGE (-1975 1350);
DISPLAY INVISIBLE (-1975 1350);
FORCEPROP 2 LAST CDS_LOCATION R8D22
J 0
(-1975 1200);
DISPLAY 0.617021 (-1975 1200);
PAINT AQUA (-1975 1200);
DISPLAY INVISIBLE (-1975 1200);
FORCEPROP 2 LAST CDS_LIB mstr_discrete
J 0
(-1925 1150);
PAINT ORANGE (-1925 1150);
DISPLAY INVISIBLE (-1925 1150);
FORCEADD RES..1
(-1425 1375);
FORCEPROP 0 LAST POP NOPOP
J 0
(-1250 1450);
DISPLAY 0.638298 (-1250 1450);
PAINT RED (-1250 1450);
FORCEPROP 1 LAST PACK_TYPE 0402
J 0
(-1275 1225);
DISPLAY 0.617021 (-1275 1225);
PAINT SKYBLUE (-1275 1225);
FORCEPROP 1 LAST PART_NUMBER G21796-074
J 0
(-1475 1475);
DISPLAY 0.617021 (-1475 1475);
PAINT BLUE (-1475 1475);
FORCEPROP 1 LAST LOCATION R8D36
J 0
(-1475 1425);
DISPLAY 0.617021 (-1475 1425);
PAINT AQUA (-1475 1425);
FORCEPROP 1 LAST MATERIAL CHIP
J 0
(-1425 1225);
DISPLAY 0.617021 (-1425 1225);
PAINT SKYBLUE (-1425 1225);
FORCEPROP 1 LAST WATTAGE 1/16W
J 2
(-1450 1225);
DISPLAY 0.617021 (-1450 1225);
PAINT SKYBLUE (-1450 1225);
FORCEPROP 1 LAST VALUE 33.2
J 2
(-1450 1275);
DISPLAY 0.617021 (-1450 1275);
PAINT SKYBLUE (-1450 1275);
FORCEPROP 1 LAST TOLERANCE 1%
J 0
(-1425 1275);
DISPLAY 0.617021 (-1425 1275);
PAINT SKYBLUE (-1425 1275);
FORCEPROP 1 LASTPIN (-1325 1375) $PN 2
J 0
(-1363 1387);
DISPLAY 0.617021 (-1363 1387);
PAINT ORANGE (-1363 1387);
FORCEPROP 1 LASTPIN (-1525 1375) $PN 1
J 0
(-1513 1387);
DISPLAY 0.617021 (-1513 1387);
PAINT ORANGE (-1513 1387);
FORCEPROP 0 LAST ROOM BMC_MISC
J 0
(-1475 1575);
DISPLAY 1.021277 (-1475 1575);
PAINT ORANGE (-1475 1575);
DISPLAY INVISIBLE (-1475 1575);
FORCEPROP 2 LAST SEC 1
J 0
(-1475 1575);
PAINT MONO (-1475 1575);
DISPLAY INVISIBLE (-1475 1575);
FORCEPROP 0 LAST BOM_COST SM
J 0
(-1475 1675);
DISPLAY 1.021277 (-1475 1675);
PAINT ORANGE (-1475 1675);
DISPLAY INVISIBLE (-1475 1675);
FORCEPROP 2 LAST SEC_TYPE 0402
J 0
(-1475 1575);
DISPLAY 1.021277 (-1475 1575);
PAINT ORANGE (-1475 1575);
DISPLAY INVISIBLE (-1475 1575);
FORCEPROP 1 LAST PATH I388
J 0
(-1475 1525);
DISPLAY 0.978723 (-1475 1525);
PAINT WHITE (-1475 1525);
DISPLAY INVISIBLE (-1475 1525);
FORCEPROP 2 LAST CDS_LIB mstr_discrete
J 0
(-1425 1375);
PAINT ORANGE (-1425 1375);
DISPLAY INVISIBLE (-1425 1375);
FORCEADD OFFPAGE..2
(-500 1375);
FORCEPROP 2 LAST $XR0 151 
J 0
(-311 1375);
DISPLAY 0.638298 (-311 1375);
PAINT MONO (-311 1375);
FORCEPROP 1 LAST OFFPAGE TRUE
J 0
(-175 1250);
DISPLAY 0.872340 (-175 1250);
PAINT GREEN (-175 1250);
DISPLAY INVISIBLE (-175 1250);
FORCEPROP 2 LAST PATH I389
J 0
(-325 1450);
DISPLAY 1.021277 (-325 1450);
PAINT ORANGE (-325 1450);
DISPLAY INVISIBLE (-325 1450);
FORCEPROP 2 LAST CDS_LIB mstr_standard
J 0
(-500 1375);
PAINT ORANGE (-500 1375);
DISPLAY INVISIBLE (-500 1375);
FORCEPROP 1 LAST COMMENT_BODY TRUE
J 0
(-545 1280);
DISPLAY 0.872340 (-545 1280);
PAINT GREEN (-545 1280);
DISPLAY INVISIBLE (-545 1280);
FORCEADD TC7PZ14FU-GP..1
(-2425 2725);
FORCEPROP 1 LAST VALUE TC7PZ14FU-GP
J 0
(-2625 2525);
DISPLAY 0.617021 (-2625 2525);
PAINT GREEN (-2625 2525);
FORCEPROP 1 LAST LOCATION U2R1
J 0
(-2625 2900);
DISPLAY 0.617021 (-2625 2900);
PAINT GREEN (-2625 2900);
FORCEPROP 2 LASTPIN (-2775 2775) $PN 1
J 2
(-2785 2785);
DISPLAY 0.808511 (-2785 2785);
PAINT ORANGE (-2785 2785);
FORCEPROP 2 LASTPIN (-2075 2775) $PN 6
J 0
(-2065 2785);
DISPLAY 0.808511 (-2065 2785);
PAINT ORANGE (-2065 2785);
FORCEPROP 2 LASTPIN (-2075 2725) $PN 5
J 0
(-2065 2735);
DISPLAY 0.808511 (-2065 2735);
PAINT ORANGE (-2065 2735);
FORCEPROP 2 LASTPIN (-2075 2675) $PN 4
J 0
(-2065 2685);
DISPLAY 0.808511 (-2065 2685);
PAINT ORANGE (-2065 2685);
FORCEPROP 2 LASTPIN (-2775 2725) $PN 2
J 2
(-2785 2735);
DISPLAY 0.808511 (-2785 2735);
PAINT ORANGE (-2785 2735);
FORCEPROP 2 LASTPIN (-2775 2675) $PN 3
J 2
(-2785 2685);
DISPLAY 0.808511 (-2785 2685);
PAINT ORANGE (-2785 2685);
FORCEPROP 1 LAST PACK_TYPE DISCRET-GA1
J 0
(-2425 2725);
DISPLAY 0.617021 (-2425 2725);
PAINT GREEN (-2425 2725);
DISPLAY INVISIBLE (-2425 2725);
FORCEPROP 1 LAST PART_NUMBER 073.7PZ14.0007
J 0
(-2425 2725);
DISPLAY 0.617021 (-2425 2725);
PAINT GREEN (-2425 2725);
DISPLAY INVISIBLE (-2425 2725);
FORCEPROP 1 LAST PATH I390
J 0
(-2425 2725);
DISPLAY 0.617021 (-2425 2725);
PAINT GREEN (-2425 2725);
DISPLAY INVISIBLE (-2425 2725);
FORCEPROP 2 LAST SEC 1
J 0
(-2625 2950);
DISPLAY 0.680851 (-2625 2950);
PAINT MONO (-2625 2950);
DISPLAY INVISIBLE (-2625 2950);
FORCEPROP 2 LAST SEC_TYPE DISCRET-GA1
J 0
(-2625 2950);
DISPLAY 1.021277 (-2625 2950);
PAINT ORANGE (-2625 2950);
DISPLAY INVISIBLE (-2625 2950);
FORCEPROP 2 LAST CDS_LIB w_hdl
J 0
(-2425 2725);
PAINT MONO (-2425 2725);
DISPLAY INVISIBLE (-2425 2725);
FORCEPROP 1 LAST CDS_LMAN_SYM_OUTLINE -200,150,200,-150
J 0
(-2425 2725);
DISPLAY 0.468085 (-2425 2725);
PAINT GREEN (-2425 2725);
DISPLAY INVISIBLE (-2425 2725);
FORCEADD RES..1
(-1250 2925);
FORCEPROP 1 LAST PACK_TYPE 0402
J 0
(-1350 2725);
DISPLAY 0.617021 (-1350 2725);
PAINT SKYBLUE (-1350 2725);
FORCEPROP 1 LAST WATTAGE 1/16W
J 2
(-1275 2775);
DISPLAY 0.617021 (-1275 2775);
PAINT SKYBLUE (-1275 2775);
FORCEPROP 1 LAST MATERIAL CHIP
J 0
(-1250 2775);
DISPLAY 0.617021 (-1250 2775);
PAINT SKYBLUE (-1250 2775);
FORCEPROP 1 LAST TOLERANCE 1%
J 0
(-1250 2825);
DISPLAY 0.617021 (-1250 2825);
PAINT SKYBLUE (-1250 2825);
FORCEPROP 1 LAST VALUE 33.2
J 2
(-1275 2825);
DISPLAY 0.617021 (-1275 2825);
PAINT SKYBLUE (-1275 2825);
FORCEPROP 1 LASTPIN (-1350 2925) $PN 1
J 0
(-1338 2937);
DISPLAY 0.617021 (-1338 2937);
PAINT ORANGE (-1338 2937);
FORCEPROP 1 LAST PART_NUMBER G21796-074
J 0
(-1350 2975);
DISPLAY 0.617021 (-1350 2975);
PAINT BLUE (-1350 2975);
FORCEPROP 1 LAST LOCATION R2R10
J 0
(-1350 3025);
DISPLAY 0.617021 (-1350 3025);
PAINT AQUA (-1350 3025);
FORCEPROP 1 LASTPIN (-1150 2925) $PN 2
J 0
(-1188 2937);
DISPLAY 0.617021 (-1188 2937);
PAINT ORANGE (-1188 2937);
FORCEPROP 0 LAST ROOM MIO_CHASSIS
J 0
(-1300 3125);
DISPLAY 1.021277 (-1300 3125);
PAINT ORANGE (-1300 3125);
DISPLAY INVISIBLE (-1300 3125);
FORCEPROP 2 LAST SEC 1
J 0
(-1300 3125);
DISPLAY 0.680851 (-1300 3125);
PAINT MONO (-1300 3125);
DISPLAY INVISIBLE (-1300 3125);
FORCEPROP 0 LAST BOM_COST MIO_CHASSIS
J 0
(-1300 3225);
DISPLAY 1.021277 (-1300 3225);
PAINT ORANGE (-1300 3225);
DISPLAY INVISIBLE (-1300 3225);
FORCEPROP 2 LAST SEC_TYPE 0402
J 0
(-1300 3125);
DISPLAY 1.021277 (-1300 3125);
PAINT ORANGE (-1300 3125);
DISPLAY INVISIBLE (-1300 3125);
FORCEPROP 2 LAST CDS_LIB mstr_discrete
J 0
(-1250 2925);
PAINT MONO (-1250 2925);
DISPLAY INVISIBLE (-1250 2925);
FORCEPROP 2 LAST CDS_LOCATION R2R10
J 0
(-1300 2975);
DISPLAY 0.617021 (-1300 2975);
PAINT AQUA (-1300 2975);
DISPLAY INVISIBLE (-1300 2975);
FORCEPROP 0 LAST CDS_SEC 1
J 0
(-1300 3075);
PAINT MONO (-1300 3075);
DISPLAY INVISIBLE (-1300 3075);
FORCEPROP 1 LAST PATH I391
J 0
(-1300 3075);
DISPLAY 0.978723 (-1300 3075);
PAINT WHITE (-1300 3075);
DISPLAY INVISIBLE (-1300 3075);
FORCEADD GND..1
(-3050 2750);
FORCEPROP 3 LASTPIN (-3050 2800) SIG_NAME GND\g
J 0
(-3040 2810);
DISPLAY 0.659574 (-3040 2810);
PAINT MONO (-3040 2810);
DISPLAY INVISIBLE (-3040 2810);
FORCEPROP 2 LAST CDS_LIB mstr_symbols
J 0
(-3050 2750);
PAINT MONO (-3050 2750);
DISPLAY INVISIBLE (-3050 2750);
FORCEPROP 1 LAST PATH I392
J 0
(-2975 2750);
DISPLAY 0.872340 (-2975 2750);
PAINT AQUA (-2975 2750);
DISPLAY INVISIBLE (-2975 2750);
FORCEPROP 1 LAST VOLTAGE 0.0V
J 0
(-3095 2707);
DISPLAY 0.340426 (-3095 2707);
PAINT SKYBLUE (-3095 2707);
DISPLAY INVISIBLE (-3095 2707);
FORCEPROP 1 LAST HDL_POWER GND
J 0
(-3050 2900);
DISPLAY 0.872340 (-3050 2900);
PAINT GREEN (-3050 2900);
DISPLAY INVISIBLE (-3050 2900);
FORCEPROP 1 LAST BODY_TYPE PLUMBING
J 0
(-3095 2707);
DISPLAY 0.340426 (-3095 2707);
PAINT GREEN (-3095 2707);
DISPLAY INVISIBLE (-3095 2707);
FORCEPROP 1 LAST SIZE 1B
J 0
(-2975 2700);
DISPLAY 0.872340 (-2975 2700);
PAINT AQUA (-2975 2700);
DISPLAY INVISIBLE (-2975 2700);
FORCEADD RES..1
(-1450 875);
FORCEPROP 1 LAST LOCATION R9E14
J 0
(-1525 975);
DISPLAY 0.617021 (-1525 975);
PAINT AQUA (-1525 975);
FORCEPROP 1 LAST TOLERANCE 5%
J 0
(-1450 725);
DISPLAY 0.617021 (-1450 725);
PAINT SKYBLUE (-1450 725);
FORCEPROP 1 LAST MATERIAL EMPTY
J 0
(-1450 675);
DISPLAY 0.617021 (-1450 675);
PAINT RED (-1450 675);
FORCEPROP 1 LAST PACK_TYPE 0402
J 0
(-1300 675);
DISPLAY 0.617021 (-1300 675);
PAINT SKYBLUE (-1300 675);
FORCEPROP 1 LAST WATTAGE 1/16W
J 2
(-1475 675);
DISPLAY 0.617021 (-1475 675);
PAINT SKYBLUE (-1475 675);
FORCEPROP 1 LAST VALUE 0.0
J 2
(-1475 725);
DISPLAY 0.617021 (-1475 725);
PAINT SKYBLUE (-1475 725);
FORCEPROP 1 LASTPIN (-1550 875) $PN 1
J 0
(-1538 887);
DISPLAY 0.617021 (-1538 887);
PAINT ORANGE (-1538 887);
FORCEPROP 1 LASTPIN (-1350 875) $PN 2
J 0
(-1388 887);
DISPLAY 0.617021 (-1388 887);
PAINT ORANGE (-1388 887);
FORCEPROP 1 LAST PART_NUMBER G21497-005
J 0
(-1525 1025);
DISPLAY 0.617021 (-1525 1025);
PAINT BLUE (-1525 1025);
FORCEPROP 2 LAST CDS_LOCATION R9E14
J 0
(-1500 925);
DISPLAY 0.617021 (-1500 925);
PAINT AQUA (-1500 925);
DISPLAY INVISIBLE (-1500 925);
FORCEPROP 0 LAST BOM_COST MEM_NV
J 0
(-1500 1175);
DISPLAY 1.021277 (-1500 1175);
PAINT ORANGE (-1500 1175);
DISPLAY INVISIBLE (-1500 1175);
FORCEPROP 2 LAST SEC_TYPE 0402
J 0
(-1500 1075);
DISPLAY 1.021277 (-1500 1075);
PAINT ORANGE (-1500 1075);
DISPLAY INVISIBLE (-1500 1075);
FORCEPROP 0 LAST ROOM NV_DIMM
J 0
(-1500 1075);
DISPLAY 1.021277 (-1500 1075);
PAINT ORANGE (-1500 1075);
DISPLAY INVISIBLE (-1500 1075);
FORCEPROP 0 LAST SEC 1
J 0
(-1500 1025);
DISPLAY 0.680851 (-1500 1025);
PAINT MONO (-1500 1025);
DISPLAY INVISIBLE (-1500 1025);
FORCEPROP 2 LAST CDS_LIB mstr_discrete
J 0
(-1450 875);
PAINT ORANGE (-1450 875);
DISPLAY INVISIBLE (-1450 875);
FORCEPROP 1 LAST PATH I393
J 0
(-1500 1025);
DISPLAY 0.978723 (-1500 1025);
PAINT WHITE (-1500 1025);
DISPLAY INVISIBLE (-1500 1025);
FORCEADD TTL1G07_A..1
(-2800 500);
FORCEPROP 1 LAST LOCATION U25W9
J 0
(-2850 700);
DISPLAY 0.617021 (-2850 700);
PAINT AQUA (-2850 700);
FORCEPROP 1 LAST VALUE 74LVC1G07
J 1
(-2800 600);
DISPLAY 0.617021 (-2800 600);
PAINT SKYBLUE (-2800 600);
FORCEPROP 1 LAST MATERIAL IC
J 0
(-2850 650);
DISPLAY 0.617021 (-2850 650);
PAINT SKYBLUE (-2850 650);
FORCEPROP 1 LAST POWER_GROUP VCC=P3V3_STBY;GND=GND
J 1
(-2850 310);
DISPLAY 0.617021 (-2850 310);
PAINT ORANGE (-2850 310);
FORCEPROP 1 LAST PART_NUMBER C88419-001
J 0
(-2850 365);
DISPLAY 0.617021 (-2850 365);
PAINT BLUE (-2850 365);
FORCEPROP 2 LASTPIN (-2650 500) $PN 4
J 0
(-2640 510);
DISPLAY 0.617021 (-2640 510);
PAINT ORANGE (-2640 510);
FORCEPROP 2 LASTPIN (-2900 500) $PN 2
J 2
(-2910 510);
DISPLAY 0.617021 (-2910 510);
PAINT ORANGE (-2910 510);
FORCEPROP 2 LAST CDS_LOCATION U25W9
J 0
(-2850 700);
DISPLAY 0.617021 (-2850 700);
PAINT AQUA (-2850 700);
DISPLAY INVISIBLE (-2850 700);
FORCEPROP 1 LAST PATH I394
J 0
(-2750 550);
DISPLAY 0.978723 (-2750 550);
PAINT WHITE (-2750 550);
DISPLAY INVISIBLE (-2750 550);
FORCEPROP 2 LAST CDS_LIB mstr_ttl
J 0
(-2800 500);
PAINT ORANGE (-2800 500);
DISPLAY INVISIBLE (-2800 500);
FORCEPROP 1 LAST PACK_TYPE SOP
J 0
(-2850 750);
DISPLAY 0.978723 (-2850 750);
PAINT SKYBLUE (-2850 750);
DISPLAY INVISIBLE (-2850 750);
FORCEPROP 2 LAST SEC_TYPE SOP
J 0
(-2850 750);
DISPLAY 1.021277 (-2850 750);
PAINT ORANGE (-2850 750);
DISPLAY INVISIBLE (-2850 750);
FORCEPROP 2 LAST SEC 1
J 0
(-2850 750);
DISPLAY 0.680851 (-2850 750);
PAINT MONO (-2850 750);
DISPLAY INVISIBLE (-2850 750);
FORCEADD P3V3_STBY..1
(-2275 900);
FORCEPROP 3 LASTPIN (-2275 850) SIG_NAME P3V3_STBY\g
J 0
(-2265 860);
DISPLAY 0.659574 (-2265 860);
PAINT MONO (-2265 860);
DISPLAY INVISIBLE (-2265 860);
FORCEPROP 1 LAST PATH I395
J 0
(-2230 902);
DISPLAY 0.340426 (-2230 902);
PAINT GREEN (-2230 902);
DISPLAY INVISIBLE (-2230 902);
FORCEPROP 1 LAST HDL_POWER P3V3_STBY
J 0
(-2575 775);
DISPLAY 0.872340 (-2575 775);
PAINT ORANGE (-2575 775);
DISPLAY INVISIBLE (-2575 775);
FORCEPROP 1 LAST VOLTAGE 3.3V
J 0
(-2320 857);
DISPLAY 0.340426 (-2320 857);
PAINT SKYBLUE (-2320 857);
DISPLAY INVISIBLE (-2320 857);
FORCEPROP 1 LAST BODY_TYPE PLUMBING
J 0
(-2320 857);
DISPLAY 0.340426 (-2320 857);
PAINT GREEN (-2320 857);
DISPLAY INVISIBLE (-2320 857);
FORCEPROP 2 LAST CDS_LIB mstr_symbols
J 0
(-2275 900);
PAINT MONO (-2275 900);
DISPLAY INVISIBLE (-2275 900);
FORCEPROP 1 LAST SIZE 1B
J 0
(-2230 922);
DISPLAY 0.340426 (-2230 922);
PAINT GREEN (-2230 922);
DISPLAY INVISIBLE (-2230 922);
FORCEADD RES..2
(-2275 700);
FORCEPROP 1 LAST WATTAGE 1/16W
J 0
(-2235 675);
DISPLAY 0.617021 (-2235 675);
PAINT SKYBLUE (-2235 675);
FORCEPROP 1 LAST PACK_TYPE 0402
J 0
(-2235 525);
DISPLAY 0.617021 (-2235 525);
PAINT SKYBLUE (-2235 525);
FORCEPROP 1 LAST PART_NUMBER G21796-072
J 0
(-2235 575);
DISPLAY 0.617021 (-2235 575);
PAINT BLUE (-2235 575);
FORCEPROP 1 LAST MATERIAL CHIP
J 0
(-2235 625);
DISPLAY 0.617021 (-2235 625);
PAINT SKYBLUE (-2235 625);
FORCEPROP 1 LAST TOLERANCE 1%
J 0
(-2230 725);
DISPLAY 0.617021 (-2230 725);
PAINT SKYBLUE (-2230 725);
FORCEPROP 1 LAST VALUE 4.75K
J 0
(-2230 775);
DISPLAY 0.617021 (-2230 775);
PAINT SKYBLUE (-2230 775);
FORCEPROP 1 LAST LOCATION R25W153
J 0
(-2230 825);
DISPLAY 0.617021 (-2230 825);
PAINT AQUA (-2230 825);
FORCEPROP 1 LASTPIN (-2275 800) $PN 1
J 0
(-2270 762);
DISPLAY 0.617021 (-2270 762);
PAINT ORANGE (-2270 762);
FORCEPROP 1 LASTPIN (-2275 600) $PN 2
J 0
(-2270 610);
DISPLAY 0.617021 (-2270 610);
PAINT ORANGE (-2270 610);
FORCEPROP 2 LAST CDS_LOCATION R25W153
J 0
(-2230 825);
DISPLAY 0.617021 (-2230 825);
PAINT AQUA (-2230 825);
DISPLAY INVISIBLE (-2230 825);
FORCEPROP 1 LAST PATH I396
J 0
(-2225 875);
DISPLAY 0.978723 (-2225 875);
PAINT WHITE (-2225 875);
DISPLAY INVISIBLE (-2225 875);
FORCEPROP 2 LAST CDS_LIB mstr_discrete
J 0
(-2275 700);
PAINT ORANGE (-2275 700);
DISPLAY INVISIBLE (-2275 700);
FORCEPROP 2 LAST SEC 1
J 0
(-2225 925);
DISPLAY 0.680851 (-2225 925);
PAINT MONO (-2225 925);
DISPLAY INVISIBLE (-2225 925);
FORCEPROP 2 LAST SEC_TYPE 0402
J 0
(-2225 925);
DISPLAY 1.021277 (-2225 925);
PAINT ORANGE (-2225 925);
DISPLAY INVISIBLE (-2225 925);
FORCEPROP 0 LAST ROOM BMC_MISC
J 0
(-2225 925);
DISPLAY 1.021277 (-2225 925);
PAINT ORANGE (-2225 925);
DISPLAY INVISIBLE (-2225 925);
FORCEPROP 0 LAST BOM_COST SM_CONTROLLER
J 0
(-2225 1025);
DISPLAY 1.021277 (-2225 1025);
PAINT ORANGE (-2225 1025);
DISPLAY INVISIBLE (-2225 1025);
FORCEADD OFFPAGE..2
(-1500 500);
FORCEPROP 2 LAST $XR2 145 
J 0
(-1311 464);
DISPLAY 0.638298 (-1311 464);
PAINT MONO (-1311 464);
FORCEPROP 2 LAST $XR1 135 
J 0
(-1191 500);
DISPLAY 0.638298 (-1191 500);
PAINT MONO (-1191 500);
FORCEPROP 2 LAST $XR0 118 
J 0
(-1311 500);
DISPLAY 0.638298 (-1311 500);
PAINT MONO (-1311 500);
FORCEPROP 2 LAST CDS_LIB mstr_standard
J 0
(-1500 500);
PAINT MONO (-1500 500);
DISPLAY INVISIBLE (-1500 500);
FORCEPROP 2 LAST PATH I397
J 0
(-1325 575);
DISPLAY 1.021277 (-1325 575);
PAINT ORANGE (-1325 575);
DISPLAY INVISIBLE (-1325 575);
FORCEPROP 1 LAST COMMENT_BODY TRUE
J 0
(-1545 405);
DISPLAY 0.872340 (-1545 405);
PAINT GREEN (-1545 405);
DISPLAY INVISIBLE (-1545 405);
FORCEPROP 1 LAST OFFPAGE TRUE
J 0
(-1175 375);
DISPLAY 0.872340 (-1175 375);
PAINT GREEN (-1175 375);
DISPLAY INVISIBLE (-1175 375);
FORCEADD RES..2
(-1850 4025);
FORCEPROP 1 LAST PACK_TYPE 0402
J 0
(-1810 3850);
DISPLAY 0.617021 (-1810 3850);
PAINT SKYBLUE (-1810 3850);
FORCEPROP 1 LAST PART_NUMBER G21796-072
J 0
(-1810 3900);
DISPLAY 0.617021 (-1810 3900);
PAINT BLUE (-1810 3900);
FORCEPROP 1 LAST MATERIAL CHIP
J 0
(-1810 3950);
DISPLAY 0.617021 (-1810 3950);
PAINT SKYBLUE (-1810 3950);
FORCEPROP 1 LAST WATTAGE 1/16W
J 0
(-1810 4000);
DISPLAY 0.617021 (-1810 4000);
PAINT SKYBLUE (-1810 4000);
FORCEPROP 1 LAST VALUE 4.75K
J 0
(-1805 4100);
DISPLAY 0.617021 (-1805 4100);
PAINT SKYBLUE (-1805 4100);
FORCEPROP 1 LAST TOLERANCE 1%
J 0
(-1805 4050);
DISPLAY 0.617021 (-1805 4050);
PAINT SKYBLUE (-1805 4050);
FORCEPROP 1 LAST LOCATION R2N27
J 0
(-1805 4150);
DISPLAY 0.617021 (-1805 4150);
PAINT AQUA (-1805 4150);
FORCEPROP 1 LASTPIN (-1850 4125) $PN 1
J 0
(-1845 4087);
DISPLAY 0.617021 (-1845 4087);
PAINT ORANGE (-1845 4087);
FORCEPROP 1 LASTPIN (-1850 3925) $PN 2
J 0
(-1845 3935);
DISPLAY 0.617021 (-1845 3935);
PAINT ORANGE (-1845 3935);
FORCEPROP 2 LAST SEC 1
J 0
(-1800 4250);
DISPLAY 0.680851 (-1800 4250);
PAINT MONO (-1800 4250);
DISPLAY INVISIBLE (-1800 4250);
FORCEPROP 2 LAST SEC_TYPE 0402
J 0
(-1800 4250);
DISPLAY 1.021277 (-1800 4250);
PAINT ORANGE (-1800 4250);
DISPLAY INVISIBLE (-1800 4250);
FORCEPROP 1 LAST PATH I97
J 0
(-1800 4200);
DISPLAY 0.978723 (-1800 4200);
PAINT WHITE (-1800 4200);
DISPLAY INVISIBLE (-1800 4200);
FORCEPROP 2 LAST ROOM BMC_MISC
J 0
(-1900 4125);
DISPLAY 1.021277 (-1900 4125);
PAINT ORANGE (-1900 4125);
DISPLAY INVISIBLE (-1900 4125);
FORCEPROP 2 LAST BOM_COST SM_CONTROLLER
J 0
(-1900 4175);
DISPLAY 1.021277 (-1900 4175);
PAINT ORANGE (-1900 4175);
DISPLAY INVISIBLE (-1900 4175);
FORCEPROP 2 LAST CDS_LOCATION R2N27
J 0
(-1805 4150);
DISPLAY 0.617021 (-1805 4150);
PAINT AQUA (-1805 4150);
DISPLAY INVISIBLE (-1805 4150);
FORCEPROP 2 LAST CDS_LIB mstr_discrete
J 0
(-1850 4025);
DISPLAY 1.361702 (-1850 4025);
PAINT ORANGE (-1850 4025);
DISPLAY INVISIBLE (-1850 4025);
FORCEADD DNS..2
(-7170 2195);
PAINT RED (-7170 2195);
FORCEPROP 2 LAST CDS_LIB mstr_misc
J 0
(-7170 2195);
PAINT ORANGE (-7170 2195);
DISPLAY INVISIBLE (-7170 2195);
FORCEPROP 1 LAST COMMENT_BODY TRUE
R 1
J 0
(-7095 1970);
DISPLAY 0.872340 (-7095 1970);
PAINT GREEN (-7095 1970);
DISPLAY INVISIBLE (-7095 1970);
FORCEADD DNS..2
(-1445 870);
PAINT RED (-1445 870);
FORCEPROP 2 LAST CDS_LIB mstr_misc
J 0
(-1445 870);
PAINT ORANGE (-1445 870);
DISPLAY INVISIBLE (-1445 870);
FORCEPROP 1 LAST COMMENT_BODY TRUE
R 1
J 0
(-1370 645);
DISPLAY 0.872340 (-1370 645);
PAINT GREEN (-1370 645);
DISPLAY INVISIBLE (-1370 645);
FORCEADD CAD_NOTE..1
(-2025 2275);
FORCEPROP 0 LAST L1 PLACE 0.1UF CAP NEXT TO VCC PIN ON 74LVC2G14
J 0
(-2175 2125);
DISPLAY 1.021277 (-2175 2125);
PAINT ORANGE (-2175 2125);
FORCEPROP 2 LAST CDS_LIB mstr_symbols
J 0
(-2025 2275);
PAINT MONO (-2025 2275);
DISPLAY INVISIBLE (-2025 2275);
FORCEPROP 1 LAST COMMENT_BODY TRUE
J 0
(-2000 2375);
DISPLAY 0.978723 (-2000 2375);
PAINT ORANGE (-2000 2375);
DISPLAY INVISIBLE (-2000 2375);
FORCEADD INTEL_CORP_BPAGE..1
(0 0);
FORCEPROP 1 LAST CDS_CON_LAST_MODIFIED Fri Jun 16 17:48:59 2017
J 0
(-1425 325);
DISPLAY 1.361702 (-1425 325);
PAINT GREEN (-1425 325);
DISPLAY INVISIBLE (-1425 325);
FORCEPROP 1 LAST CUSTOM_TXT_CDS <CURRENT_DESIGN_SHEET> OF <TOTAL_DESIGN_SHEETS>
J 0
(-500 25);
PAINT ORANGE (-500 25);
FORCEPROP 1 LAST CUSTOM_TXT_CDS <CON_LAST_MODIFIED>
J 0
(-4000 100);
PAINT ORANGE (-4000 100);
FORCEPROP 2 LAST CUSTOM_TXT_CDS <XR_PAGE_TITLE>
J 0
(-7890 5250);
DISPLAY 0.638298 (-7890 5250);
PAINT PINK (-7890 5250);
DISPLAY INVISIBLE (-7890 5250);
FORCEPROP 1 LAST SCH_TITLE BMC MISC (2 OF 2)
J 0
(-7950 50);
DISPLAY 1.212766 (-7950 50);
PAINT ORANGE (-7950 50);
FORCEPROP 1 LAST COMMENT_BODY TRUE
J 0
(12 12);
DISPLAY 0.617021 (12 12);
PAINT GREEN (12 12);
DISPLAY INVISIBLE (12 12);
FORCEPROP 2 LAST CDS_LIB mstr_symbols
J 0
(0 0);
DISPLAY 1.361702 (0 0);
PAINT ORANGE (0 0);
DISPLAY INVISIBLE (0 0);
FORCEPROP 2 LAST PAGE_BORDER TRUE
J 0
(-7890 5250);
DISPLAY 0.851064 (-7890 5250);
PAINT PINK (-7890 5250);
DISPLAY INVISIBLE (-7890 5250);
FORCEPROP 2 LAST CDS_XR_PAGE_TITLE CR-157 : @BASEBOARD_FAB2_LIB.BASEBOARD_FAB2(SCH_1):PAGE157
J 0
(-7890 5250);
DISPLAY 0.638298 (-7890 5250);
PAINT PINK (-7890 5250);
DISPLAY INVISIBLE (-7890 5250);
FORCEADD CAD_NOTE..1
(-900 1825);
FORCEPROP 0 LAST L2 NEXT TO VCC PIN OF
J 2
(-675 1625);
DISPLAY 1.021277 (-675 1625);
PAINT ORANGE (-675 1625);
FORCEPROP 0 LAST L1 PLACE 0.1UF CAP
J 2
(-675 1700);
DISPLAY 1.021277 (-675 1700);
PAINT ORANGE (-675 1700);
FORCEPROP 0 LAST L3 TTL1G07_A
J 2
(-675 1550);
DISPLAY 1.021277 (-675 1550);
PAINT ORANGE (-675 1550);
FORCEPROP 2 LAST CDS_LIB mstr_symbols
J 0
(-900 1825);
PAINT ORANGE (-900 1825);
DISPLAY INVISIBLE (-900 1825);
FORCEPROP 1 LAST COMMENT_BODY TRUE
J 0
(-875 1925);
DISPLAY 0.978723 (-875 1925);
PAINT ORANGE (-875 1925);
DISPLAY INVISIBLE (-875 1925);
WIRE 16 -1 (-7525 4600)(-7525 4225);
WIRE 16 -1 (-7525 4225)(-7525 3975);
WIRE 16 -1 (-7525 4225)(-7300 4225);
WIRE 16 -1 (-7525 3975)(-7525 3725);
WIRE 16 -1 (-7525 3975)(-7275 3975);
WIRE 16 -1 (-7525 3425)(-7525 3725);
WIRE 16 -1 (-7525 3725)(-7275 3725);
WIRE 16 -1 (-7525 3100)(-7525 3425);
WIRE 16 -1 (-7525 3425)(-7275 3425);
WIRE 16 -1 (-7525 2875)(-7525 3100);
WIRE 16 -1 (-7525 3100)(-7275 3100);
WIRE 16 -1 (-7525 2650)(-7525 2875);
WIRE 16 -1 (-7525 2875)(-7275 2875);
WIRE 16 -1 (-7525 2425)(-7525 2650);
WIRE 16 -1 (-7525 2650)(-7275 2650);
WIRE 16 -1 (-7525 2200)(-7525 2425);
WIRE 16 -1 (-7525 2425)(-7275 2425);
WIRE 16 -1 (-7525 2200)(-7275 2200);
WIRE 16 -1 (-1850 4125)(-1850 4225);
WIRE 16 -1 (-6150 675)(-6150 575);
WIRE 16 -1 (-6150 1350)(-6150 1400);
WIRE 16 -1 (-5500 1750)(-5500 1825);
WIRE 16 -1 (-5500 825)(-5500 900);
WIRE 16 -1 (-2275 1625)(-2275 1675);
WIRE 16 -1 (-3225 2225)(-3225 2350);
WIRE 16 -1 (-4925 2550)(-4925 2675);
WIRE 16 -1 (-4925 2675)(-4775 2675);
WIRE 16 -1 (-5250 4625)(-5250 4025);
WIRE 16 -1 (-5250 4025)(-5025 4025);
WIRE 16 -1 (-1700 2775)(-1700 2725);
WIRE 16 -1 (-2075 2725)(-1700 2725);
WIRE 16 -1 (-1700 2725)(-1700 2675);
WIRE 16 -1 (-1700 2425)(-1700 2475);
WIRE 16 -1 (-500 1650)(-500 1625);
WIRE 16 -1 (-500 1900)(-500 1850);
WIRE 16 -1 (-3975 3050)(-3975 3175);
WIRE 16 -1 (-3050 2800)(-3050 2850);
WIRE 16 -1 (-3050 2850)(-3000 2850);
WIRE 16 -1 (-3000 2850)(-3000 2725);
WIRE 16 -1 (-3000 2725)(-2775 2725);
WIRE 16 -1 (-2275 850)(-2275 800);
WIRE 3 2175 (-5000 2075)(-225 2075);
WIRE 3 2175 (-225 3350)(-225 2075);
WIRE 3 2175 (-5000 3350)(-5000 2075);
WIRE 3 2175 (-5000 3350)(-225 3350);
WIRE 16 -1 (-1325 1375)(-550 1375);
FORCEPROP 2 LAST SIG_NAME RST_BMC_DDR3_BUF_IN_N
J 0
(-1260 1385);
DISPLAY 0.617021 (-1260 1385);
PAINT ORANGE (-1260 1385);
WIRE 16 -1 (-2075 1375)(-1525 1375);
WIRE 16 -1 (-2075 1150)(-2075 1375);
WIRE 16 -1 (-2025 1150)(-2075 1150);
WIRE 16 -1 (-2075 1150)(-2275 1150);
WIRE 16 -1 (-2275 1425)(-2275 1150);
WIRE 16 -1 (-2650 1150)(-2275 1150);
WIRE 3 2175 (-1750 1075)(-225 1075);
WIRE 3 2175 (-225 1225)(-225 1075);
WIRE 3 2175 (-1750 1225)(-1750 1075);
WIRE 3 2175 (-1750 1225)(-225 1225);
WIRE 16 3135 (-2775 2125)(-150 2125);
WIRE 16 3135 (-2775 1800)(-2775 2125);
WIRE 16 3135 (-5050 1800)(-5050 3025);
WIRE 16 3135 (-5050 1800)(-2775 1800);
WIRE 16 -1 (-7075 2650)(-6000 2650);
FORCEPROP 2 LAST SIG_NAME FM_ADR_SMI_GPIO_N
J 0
(-6860 2660);
DISPLAY 0.617021 (-6860 2660);
PAINT ORANGE (-6860 2660);
WIRE 16 -1 (-7075 2425)(-6000 2425);
FORCEPROP 2 LAST SIG_NAME FM_BMC_CPLD_GPO
J 0
(-6860 2435);
DISPLAY 0.617021 (-6860 2435);
PAINT ORANGE (-6860 2435);
WIRE 16 -1 (-7075 3425)(-6000 3425);
FORCEPROP 2 LAST SIG_NAME FM_BMC_CPLD_MP_RST_N
J 0
(-6860 3435);
DISPLAY 0.617021 (-6860 3435);
PAINT ORANGE (-6860 3435);
WIRE 16 -1 (-7100 4225)(-6025 4225);
FORCEPROP 2 LAST SIG_NAME IRQ_MEZZ_LAN_ALERT_N
J 0
(-6910 4235);
DISPLAY 0.617021 (-6910 4235);
PAINT ORANGE (-6910 4235);
WIRE 16 -1 (-7075 3725)(-6000 3725);
FORCEPROP 2 LAST SIG_NAME FP_NMI_BTN_N
J 0
(-6860 3735);
DISPLAY 0.617021 (-6860 3735);
PAINT ORANGE (-6860 3735);
WIRE 16 -1 (-7075 3100)(-6000 3100);
FORCEPROP 2 LAST SIG_NAME FM_MP_PS_FAIL_N
J 0
(-6860 3110);
DISPLAY 0.617021 (-6860 3110);
PAINT ORANGE (-6860 3110);
WIRE 16 -1 (-7075 2875)(-6000 2875);
FORCEPROP 2 LAST SIG_NAME FM_MP_PS_REDUNDANT_LOST_N
J 0
(-6860 2885);
DISPLAY 0.617021 (-6860 2885);
PAINT ORANGE (-6860 2885);
WIRE 16 -1 (-6300 775)(-6875 775);
FORCEPROP 2 LAST SIG_NAME H_CPU0_FAST_WAKE_B_N
J 0
(-6835 785);
DISPLAY 0.617021 (-6835 785);
PAINT ORANGE (-6835 785);
FORCEPROP 2 LASTPROP $XRERR UNIQUE?
J 0
(-7075 785);
DISPLAY 0.638298 (-7075 785);
PAINT MONO (-7075 785);
DISPLAY INVISIBLE (-7075 785);
WIRE 16 -1 (-6150 875)(-6150 1000);
WIRE 16 -1 (-6150 1000)(-6150 1150);
WIRE 16 -1 (-6150 1000)(-5700 1000);
FORCEPROP 2 LAST SIG_NAME H_CPU0_FAST_WAKE
J 0
(-6135 1010);
DISPLAY 0.617021 (-6135 1010);
PAINT ORANGE (-6135 1010);
FORCEPROP 2 LASTPROP $XRERR UNIQUE?
J 0
(-6375 1010);
DISPLAY 0.638298 (-6375 1010);
PAINT MONO (-6375 1010);
DISPLAY INVISIBLE (-6375 1010);
WIRE 16 -1 (-5500 1425)(-5500 1300);
WIRE 16 -1 (-5500 1425)(-5500 1550);
WIRE 16 -1 (-5500 1425)(-4825 1425);
FORCEPROP 2 LAST SIG_NAME H_CPU0_FAST_WAKE_LVT3_N
J 0
(-5385 1435);
DISPLAY 0.617021 (-5385 1435);
PAINT ORANGE (-5385 1435);
WIRE 16 3135 (-4400 375)(-4400 1750);
WIRE 16 -1 (-3100 500)(-2900 500);
WIRE 16 -1 (-3100 1150)(-3100 500);
WIRE 16 -1 (-3100 1150)(-2900 1150);
WIRE 16 -1 (-3450 1150)(-3100 1150);
FORCEPROP 2 LAST SIG_NAME PWRGD_DSW_PWROK
J 0
(-3385 1160);
DISPLAY 0.617021 (-3385 1160);
PAINT ORANGE (-3385 1160);
WIRE 16 -1 (-2275 600)(-2275 500);
WIRE 16 -1 (-2275 500)(-1550 500);
FORCEPROP 2 LAST SIG_NAME RST_BMC_SRST_N
J 0
(-2010 510);
DISPLAY 0.638298 (-2010 510);
PAINT ORANGE (-2010 510);
WIRE 16 -1 (-2650 500)(-2275 500);
WIRE 3 682 (-2550 850)(-2550 1000);
WIRE 3 682 (-3200 850)(-2550 850);
WIRE 3 682 (-2550 1000)(-2000 1000);
WIRE 3 682 (-2000 1000)(-2000 650);
WIRE 3 682 (-3200 350)(-3200 850);
WIRE 3 682 (-1050 350)(-3200 350);
WIRE 3 682 (-2000 650)(-1050 650);
WIRE 3 682 (-1050 650)(-1050 350);
WIRE 16 -1 (-1600 875)(-1550 875);
WIRE 16 -1 (-1600 875)(-1600 1150);
WIRE 16 -1 (-1825 1150)(-1600 1150);
WIRE 16 -1 (-850 1150)(-1600 1150);
FORCEPROP 2 LAST SIG_NAME FM_TPM_PRES_RST_N
J 0
(-1435 1160);
DISPLAY 0.680851 (-1435 1160);
PAINT ORANGE (-1435 1160);
WIRE 16 -1 (-2775 2775)(-2900 2775);
WIRE 16 -1 (-2075 2675)(-1950 2675);
WIRE 16 -1 (-1950 2425)(-1950 2675);
WIRE 16 -1 (-2900 2775)(-2900 2425);
WIRE 16 -1 (-2900 2425)(-1950 2425);
FORCEPROP 2 LAST SIG_NAME FP_NMI_BTN
J 0
(-2560 2435);
DISPLAY 0.617021 (-2560 2435);
PAINT ORANGE (-2560 2435);
FORCEPROP 2 LASTPROP $XRERR UNIQUE?
J 0
(-2800 2435);
DISPLAY 0.638298 (-2800 2435);
PAINT MONO (-2800 2435);
DISPLAY INVISIBLE (-2800 2435);
WIRE 16 -1 (-3975 2675)(-4275 2675);
FORCEPROP 2 LAST SIG_NAME FP_NMI_BTN_OUT_R_N
J 0
(-4310 2685);
DISPLAY 0.617021 (-4310 2685);
PAINT ORANGE (-4310 2685);
FORCEPROP 2 LASTPROP $XRERR UNIQUE?
J 0
(-4550 2685);
DISPLAY 0.638298 (-4550 2685);
PAINT MONO (-4550 2685);
DISPLAY INVISIBLE (-4550 2685);
WIRE 16 -1 (-3975 2850)(-3975 2675);
WIRE 16 -1 (-3775 2675)(-3975 2675);
WIRE 16 -1 (-2075 2775)(-1950 2775);
WIRE 16 -1 (-1950 2775)(-1950 2925);
WIRE 16 -1 (-1950 2925)(-1350 2925);
FORCEPROP 2 LAST SIG_NAME FP_NMI_BTN_R_N
J 0
(-1840 2944);
DISPLAY 0.617021 (-1840 2944);
PAINT ORANGE (-1840 2944);
FORCEPROP 2 LASTPROP $XRERR UNIQUE?
J 0
(-2080 2944);
DISPLAY 0.638298 (-2080 2944);
PAINT MONO (-2080 2944);
DISPLAY INVISIBLE (-2080 2944);
WIRE 16 3135 (-5050 3425)(-125 3425);
WIRE 16 3135 (-5050 3050)(-5050 3425);
WIRE 16 -1 (-4825 4025)(-3750 4025);
FORCEPROP 2 LAST SIG_NAME FM_CPLD_BMC_PWRDN_N
J 0
(-4610 4035);
DISPLAY 0.617021 (-4610 4035);
PAINT ORANGE (-4610 4035);
WIRE 16 -1 (-1950 3825)(-1850 3825);
WIRE 16 -1 (-1850 3825)(-1300 3825);
FORCEPROP 2 LAST SIG_NAME FM_BMC_NMI_N
J 0
(-1585 3835);
DISPLAY 0.617021 (-1585 3835);
PAINT ORANGE (-1585 3835);
WIRE 16 -1 (-1850 3925)(-1850 3825);
WIRE 16 -1 (-1150 2925)(-650 2925);
FORCEPROP 2 LAST SIG_NAME FP_NMI_BTN_N
J 0
(-1060 2935);
DISPLAY 0.617021 (-1060 2935);
PAINT ORANGE (-1060 2935);
WIRE 16 -1 (-1350 875)(-850 875);
FORCEPROP 2 LAST SIG_NAME FM_BMC_ENABLE_N
J 0
(-1260 885);
DISPLAY 0.617021 (-1260 885);
PAINT ORANGE (-1260 885);
WIRE 16 -1 (-3225 2550)(-3225 2675);
WIRE 16 -1 (-3225 2675)(-2775 2675);
WIRE 16 -1 (-3575 2675)(-3225 2675);
FORCEPROP 2 LAST SIG_NAME FP_NMI_BTN_OUT_N
J 0
(-3560 2685);
DISPLAY 0.617021 (-3560 2685);
PAINT ORANGE (-3560 2685);
FORCEPROP 2 LASTPROP $XRERR UNIQUE?
J 0
(-3800 2685);
DISPLAY 0.638298 (-3800 2685);
PAINT MONO (-3800 2685);
DISPLAY INVISIBLE (-3800 2685);
WIRE 16 -1 (-7525 775)(-7075 775);
FORCEPROP 2 LAST SIG_NAME H_CPU0_FAST_WAKE_N
J 0
(-7510 785);
DISPLAY 0.617021 (-7510 785);
PAINT ORANGE (-7510 785);
WIRE 16 -1 (-2850 3825)(-2150 3825);
FORCEPROP 2 LAST SIG_NAME FM_NMI_EVENT_N
J 0
(-2860 3835);
DISPLAY 0.617021 (-2860 3835);
PAINT ORANGE (-2860 3835);
WIRE 16 -1 (-7075 2200)(-6000 2200);
FORCEPROP 2 LAST SIG_NAME FM_BIOS_TOP_SWAP
J 0
(-6860 2210);
DISPLAY 0.617021 (-6860 2210);
PAINT ORANGE (-6860 2210);
WIRE 16 -1 (-7075 3975)(-6000 3975);
FORCEPROP 2 LAST SIG_NAME IRQ_OOB_MGMT_RISER_ALERT_N
J 0
(-6885 3985);
DISPLAY 0.617021 (-6885 3985);
PAINT ORANGE (-6885 3985);
DOT 1 (-2275 500);
DOT 1 (-1600 1150);
DOT 1 (-3225 2675);
DOT 1 (-3975 2675);
DOT 1 (-1700 2725);
DOT 1 (-6150 1000);
DOT 1 (-5500 1425);
DOT 1 (-7525 2425);
DOT 1 (-7525 2875);
DOT 1 (-7525 2650);
DOT 1 (-7525 3100);
DOT 1 (-7525 3425);
DOT 1 (-7525 3725);
DOT 1 (-7525 3975);
DOT 1 (-7525 4225);
DOT 1 (-1850 3825);
DOT 1 (-3100 1150);
DOT 1 (-2275 1150);
DOT 1 (-2075 1150);
FORCENOTE
BMC DISABLE JUMPER (ON PAGE 134 PINS 3 AND 5)
(-4275 1625) 0;
DISPLAY LEFT (-4275 1625);
DISPLAY 1.276596 (-4275 1625);
PAINT PURPLE (-4275 1625);
FORCENOTE
TP FAB1 NOPOP R9E14 0121
(-1350 750) 0;
DISPLAY LEFT (-1350 750);
DISPLAY 1.021277 (-1350 750);
PAINT RED (-1350 750);
FORCENOTE
NMI BUTTON
(-4800 3175) 0;
DISPLAY LEFT (-4800 3175);
DISPLAY 1.021277 (-4800 3175);
PAINT PURPLE (-4800 3175);
FORCENOTE
TP FAB1 CHANGE U2R1 PN 1222
(-4925 3375) 0;
DISPLAY LEFT (-4925 3375);
DISPLAY 1.021277 (-4925 3375);
PAINT RED (-4925 3375);
FORCENOTE
ROOM=SM_CONTROLLER
(-7764 315) 0;
DISPLAY LEFT (-7764 315);
DISPLAY 0.617021 (-7764 315);
PAINT PURPLE (-7764 315);
FORCENOTE
TP FAB1 ADD CIRCUIT 0228
(-1025 350) 0;
DISPLAY LEFT (-1025 350);
DISPLAY 1.021277 (-1025 350);
PAINT RED (-1025 350);
FORCENOTE
TP FAB1 FOR BMC TPM 1120
(-1150 1250) 0;
DISPLAY LEFT (-1150 1250);
DISPLAY 1.021277 (-1150 1250);
PAINT RED (-1150 1250);
FORCENOTE
TP FAB4 NOPOP R8D36 20170206
(-1050 1450) 0;
DISPLAY LEFT (-1050 1450);
DISPLAY 0.638298 (-1050 1450);
PAINT RED (-1050 1450);
QUIT
